FILE_TYPE = MACRO_DRAWING;
SET COLOR_WIRE YELLOW;
SET COLOR_PROP MONO;
SET COLOR_DOT WHITE;
SET COLOR_ARC YELLOW;
SET COLOR_BODY GREEN;
SET COLOR_NOTE MONO;
SET PROP_DISPLAY VALUE;
SET PAGE_NUMBER P30;
FORCEADD TAP..1
R 2
(-5825 1900);
FORCEPROP 3 LASTPIN (-5775 1900) SIG_NAME P3E_CPU0_PE1_SS_RXP<1>
J 0
(-5765 1910);
DISPLAY 0.659574 (-5765 1910);
PAINT MONO (-5765 1910);
DISPLAY INVISIBLE (-5765 1910);
FORCEPROP 1 LASTPIN (-5775 1900) BN 1
J 2
(-5763 1908);
DISPLAY 0.617021 (-5763 1908);
PAINT PINK (-5763 1908);
FORCEPROP 2 LAST CDS_LIB mstr_standard
J 0
(-5825 1900);
PAINT MONO (-5825 1900);
DISPLAY INVISIBLE (-5825 1900);
FORCEPROP 1 LAST BODY_TYPE PLUMBING
J 2
(-5825 1950);
DISPLAY 1.446809 (-5825 1950);
PAINT GREEN (-5825 1950);
DISPLAY INVISIBLE (-5825 1950);
FORCEPROP 1 LAST HDL_TAP TRUE
J 2
(-6150 1775);
DISPLAY 1.446809 (-6150 1775);
PAINT GREEN (-6150 1775);
DISPLAY INVISIBLE (-6150 1775);
FORCEPROP 1 LAST PATH I1
J 2
(-5823 1900);
DISPLAY 0.872340 (-5823 1900);
PAINT GREEN (-5823 1900);
DISPLAY INVISIBLE (-5823 1900);
FORCEADD TAP..1
R 2
(-5825 2500);
FORCEPROP 3 LASTPIN (-5775 2500) SIG_NAME P3E_CPU0_PE1_SS_RXP<7>
J 0
(-5765 2510);
DISPLAY 0.659574 (-5765 2510);
PAINT MONO (-5765 2510);
DISPLAY INVISIBLE (-5765 2510);
FORCEPROP 1 LASTPIN (-5775 2500) BN 7
J 2
(-5763 2508);
DISPLAY 0.617021 (-5763 2508);
PAINT PINK (-5763 2508);
FORCEPROP 2 LAST CDS_LIB mstr_standard
J 0
(-5825 2500);
PAINT MONO (-5825 2500);
DISPLAY INVISIBLE (-5825 2500);
FORCEPROP 1 LAST BODY_TYPE PLUMBING
J 2
(-5825 2550);
DISPLAY 1.446809 (-5825 2550);
PAINT GREEN (-5825 2550);
DISPLAY INVISIBLE (-5825 2550);
FORCEPROP 1 LAST HDL_TAP TRUE
J 2
(-6150 2375);
DISPLAY 1.446809 (-6150 2375);
PAINT GREEN (-6150 2375);
DISPLAY INVISIBLE (-6150 2375);
FORCEPROP 1 LAST PATH I10
J 2
(-5823 2500);
DISPLAY 0.872340 (-5823 2500);
PAINT GREEN (-5823 2500);
DISPLAY INVISIBLE (-5823 2500);
FORCEADD TAP..1
R 2
(-5825 2850);
FORCEPROP 3 LASTPIN (-5775 2850) SIG_NAME P3E_CPU0_PE1_PCH_RXP<8>
J 0
(-5765 2860);
DISPLAY 0.659574 (-5765 2860);
PAINT MONO (-5765 2860);
DISPLAY INVISIBLE (-5765 2860);
FORCEPROP 1 LASTPIN (-5775 2850) BN 8
J 2
(-5763 2858);
DISPLAY 0.617021 (-5763 2858);
PAINT PINK (-5763 2858);
FORCEPROP 2 LAST CDS_LIB mstr_standard
J 0
(-5825 2850);
PAINT MONO (-5825 2850);
DISPLAY INVISIBLE (-5825 2850);
FORCEPROP 1 LAST BODY_TYPE PLUMBING
J 2
(-5825 2900);
DISPLAY 1.446809 (-5825 2900);
PAINT GREEN (-5825 2900);
DISPLAY INVISIBLE (-5825 2900);
FORCEPROP 1 LAST HDL_TAP TRUE
J 2
(-6150 2725);
DISPLAY 1.446809 (-6150 2725);
PAINT GREEN (-6150 2725);
DISPLAY INVISIBLE (-6150 2725);
FORCEPROP 1 LAST PATH I11
J 2
(-5823 2850);
DISPLAY 0.872340 (-5823 2850);
PAINT GREEN (-5823 2850);
DISPLAY INVISIBLE (-5823 2850);
FORCEADD TAP..1
R 2
(-5825 2900);
FORCEPROP 3 LASTPIN (-5775 2900) SIG_NAME P3E_CPU0_PE1_PCH_RXP<9>
J 0
(-5765 2910);
DISPLAY 0.659574 (-5765 2910);
PAINT MONO (-5765 2910);
DISPLAY INVISIBLE (-5765 2910);
FORCEPROP 1 LASTPIN (-5775 2900) BN 9
J 2
(-5763 2908);
DISPLAY 0.617021 (-5763 2908);
PAINT PINK (-5763 2908);
FORCEPROP 2 LAST CDS_LIB mstr_standard
J 0
(-5825 2900);
PAINT MONO (-5825 2900);
DISPLAY INVISIBLE (-5825 2900);
FORCEPROP 1 LAST BODY_TYPE PLUMBING
J 2
(-5825 2950);
DISPLAY 1.446809 (-5825 2950);
PAINT GREEN (-5825 2950);
DISPLAY INVISIBLE (-5825 2950);
FORCEPROP 1 LAST HDL_TAP TRUE
J 2
(-6150 2775);
DISPLAY 1.446809 (-6150 2775);
PAINT GREEN (-6150 2775);
DISPLAY INVISIBLE (-6150 2775);
FORCEPROP 1 LAST PATH I12
J 2
(-5823 2900);
DISPLAY 0.872340 (-5823 2900);
PAINT GREEN (-5823 2900);
DISPLAY INVISIBLE (-5823 2900);
FORCEADD TAP..1
R 2
(-5825 2950);
FORCEPROP 3 LASTPIN (-5775 2950) SIG_NAME P3E_CPU0_PE1_PCH_RXP<10>
J 0
(-5765 2960);
DISPLAY 0.659574 (-5765 2960);
PAINT MONO (-5765 2960);
DISPLAY INVISIBLE (-5765 2960);
FORCEPROP 1 LASTPIN (-5775 2950) BN 10
J 2
(-5763 2958);
DISPLAY 0.617021 (-5763 2958);
PAINT PINK (-5763 2958);
FORCEPROP 2 LAST CDS_LIB mstr_standard
J 0
(-5825 2950);
PAINT MONO (-5825 2950);
DISPLAY INVISIBLE (-5825 2950);
FORCEPROP 1 LAST BODY_TYPE PLUMBING
J 2
(-5825 3000);
DISPLAY 1.446809 (-5825 3000);
PAINT GREEN (-5825 3000);
DISPLAY INVISIBLE (-5825 3000);
FORCEPROP 1 LAST HDL_TAP TRUE
J 2
(-6150 2825);
DISPLAY 1.446809 (-6150 2825);
PAINT GREEN (-6150 2825);
DISPLAY INVISIBLE (-6150 2825);
FORCEPROP 1 LAST PATH I13
J 2
(-5823 2950);
DISPLAY 0.872340 (-5823 2950);
PAINT GREEN (-5823 2950);
DISPLAY INVISIBLE (-5823 2950);
FORCEADD TAP..1
R 2
(-5825 3000);
FORCEPROP 3 LASTPIN (-5775 3000) SIG_NAME P3E_CPU0_PE1_PCH_RXP<11>
J 0
(-5765 3010);
DISPLAY 0.659574 (-5765 3010);
PAINT MONO (-5765 3010);
DISPLAY INVISIBLE (-5765 3010);
FORCEPROP 1 LASTPIN (-5775 3000) BN 11
J 2
(-5763 3008);
DISPLAY 0.617021 (-5763 3008);
PAINT PINK (-5763 3008);
FORCEPROP 2 LAST CDS_LIB mstr_standard
J 0
(-5825 3000);
PAINT MONO (-5825 3000);
DISPLAY INVISIBLE (-5825 3000);
FORCEPROP 1 LAST BODY_TYPE PLUMBING
J 2
(-5825 3050);
DISPLAY 1.446809 (-5825 3050);
PAINT GREEN (-5825 3050);
DISPLAY INVISIBLE (-5825 3050);
FORCEPROP 1 LAST HDL_TAP TRUE
J 2
(-6150 2875);
DISPLAY 1.446809 (-6150 2875);
PAINT GREEN (-6150 2875);
DISPLAY INVISIBLE (-6150 2875);
FORCEPROP 1 LAST PATH I14
J 2
(-5823 3000);
DISPLAY 0.872340 (-5823 3000);
PAINT GREEN (-5823 3000);
DISPLAY INVISIBLE (-5823 3000);
FORCEADD TAP..1
R 2
(-5825 3350);
FORCEPROP 3 LASTPIN (-5775 3350) SIG_NAME P3E_CPU0_PE1_PCH_RXP<12>
J 0
(-5765 3360);
DISPLAY 0.659574 (-5765 3360);
PAINT MONO (-5765 3360);
DISPLAY INVISIBLE (-5765 3360);
FORCEPROP 1 LASTPIN (-5775 3350) BN 12
J 2
(-5763 3358);
DISPLAY 0.617021 (-5763 3358);
PAINT PINK (-5763 3358);
FORCEPROP 2 LAST CDS_LIB mstr_standard
J 0
(-5825 3350);
PAINT MONO (-5825 3350);
DISPLAY INVISIBLE (-5825 3350);
FORCEPROP 1 LAST BODY_TYPE PLUMBING
J 2
(-5825 3400);
DISPLAY 1.446809 (-5825 3400);
PAINT GREEN (-5825 3400);
DISPLAY INVISIBLE (-5825 3400);
FORCEPROP 1 LAST HDL_TAP TRUE
J 2
(-6150 3225);
DISPLAY 1.446809 (-6150 3225);
PAINT GREEN (-6150 3225);
DISPLAY INVISIBLE (-6150 3225);
FORCEPROP 1 LAST PATH I15
J 2
(-5823 3350);
DISPLAY 0.872340 (-5823 3350);
PAINT GREEN (-5823 3350);
DISPLAY INVISIBLE (-5823 3350);
FORCEADD TAP..1
R 2
(-5825 3400);
FORCEPROP 3 LASTPIN (-5775 3400) SIG_NAME P3E_CPU0_PE1_PCH_RXP<13>
J 0
(-5765 3410);
DISPLAY 0.659574 (-5765 3410);
PAINT MONO (-5765 3410);
DISPLAY INVISIBLE (-5765 3410);
FORCEPROP 1 LASTPIN (-5775 3400) BN 13
J 2
(-5763 3408);
DISPLAY 0.617021 (-5763 3408);
PAINT PINK (-5763 3408);
FORCEPROP 2 LAST CDS_LIB mstr_standard
J 0
(-5825 3400);
PAINT MONO (-5825 3400);
DISPLAY INVISIBLE (-5825 3400);
FORCEPROP 1 LAST BODY_TYPE PLUMBING
J 2
(-5825 3450);
DISPLAY 1.446809 (-5825 3450);
PAINT GREEN (-5825 3450);
DISPLAY INVISIBLE (-5825 3450);
FORCEPROP 1 LAST HDL_TAP TRUE
J 2
(-6150 3275);
DISPLAY 1.446809 (-6150 3275);
PAINT GREEN (-6150 3275);
DISPLAY INVISIBLE (-6150 3275);
FORCEPROP 1 LAST PATH I16
J 2
(-5823 3400);
DISPLAY 0.872340 (-5823 3400);
PAINT GREEN (-5823 3400);
DISPLAY INVISIBLE (-5823 3400);
FORCEADD TAP..1
R 2
(-5825 3500);
FORCEPROP 3 LASTPIN (-5775 3500) SIG_NAME P3E_CPU0_PE1_PCH_RXP<15>
J 0
(-5765 3510);
DISPLAY 0.659574 (-5765 3510);
PAINT MONO (-5765 3510);
DISPLAY INVISIBLE (-5765 3510);
FORCEPROP 1 LASTPIN (-5775 3500) BN 15
J 2
(-5763 3508);
DISPLAY 0.617021 (-5763 3508);
PAINT PINK (-5763 3508);
FORCEPROP 2 LAST CDS_LIB mstr_standard
J 0
(-5825 3500);
PAINT MONO (-5825 3500);
DISPLAY INVISIBLE (-5825 3500);
FORCEPROP 1 LAST BODY_TYPE PLUMBING
J 2
(-5825 3550);
DISPLAY 1.446809 (-5825 3550);
PAINT GREEN (-5825 3550);
DISPLAY INVISIBLE (-5825 3550);
FORCEPROP 1 LAST HDL_TAP TRUE
J 2
(-6150 3375);
DISPLAY 1.446809 (-6150 3375);
PAINT GREEN (-6150 3375);
DISPLAY INVISIBLE (-6150 3375);
FORCEPROP 1 LAST PATH I17
J 2
(-5823 3500);
DISPLAY 0.872340 (-5823 3500);
PAINT GREEN (-5823 3500);
DISPLAY INVISIBLE (-5823 3500);
FORCEADD TAP..1
R 2
(-5825 3450);
FORCEPROP 3 LASTPIN (-5775 3450) SIG_NAME P3E_CPU0_PE1_PCH_RXP<14>
J 0
(-5765 3460);
DISPLAY 0.659574 (-5765 3460);
PAINT MONO (-5765 3460);
DISPLAY INVISIBLE (-5765 3460);
FORCEPROP 1 LASTPIN (-5775 3450) BN 14
J 2
(-5763 3458);
DISPLAY 0.617021 (-5763 3458);
PAINT PINK (-5763 3458);
FORCEPROP 2 LAST CDS_LIB mstr_standard
J 0
(-5825 3450);
PAINT MONO (-5825 3450);
DISPLAY INVISIBLE (-5825 3450);
FORCEPROP 1 LAST BODY_TYPE PLUMBING
J 2
(-5825 3500);
DISPLAY 1.446809 (-5825 3500);
PAINT GREEN (-5825 3500);
DISPLAY INVISIBLE (-5825 3500);
FORCEPROP 1 LAST HDL_TAP TRUE
J 2
(-6150 3325);
DISPLAY 1.446809 (-6150 3325);
PAINT GREEN (-6150 3325);
DISPLAY INVISIBLE (-6150 3325);
FORCEPROP 1 LAST PATH I18
J 2
(-5823 3450);
DISPLAY 0.872340 (-5823 3450);
PAINT GREEN (-5823 3450);
DISPLAY INVISIBLE (-5823 3450);
FORCEADD TAP..1
R 2
(-5550 1650);
FORCEPROP 3 LASTPIN (-5500 1650) SIG_NAME P3E_CPU0_PE1_SS_RXN<1>
J 0
(-5490 1660);
DISPLAY 0.659574 (-5490 1660);
PAINT MONO (-5490 1660);
DISPLAY INVISIBLE (-5490 1660);
FORCEPROP 1 LASTPIN (-5500 1650) BN 1
J 2
(-5488 1658);
DISPLAY 0.617021 (-5488 1658);
PAINT PINK (-5488 1658);
FORCEPROP 2 LAST CDS_LIB mstr_standard
J 0
(-5550 1650);
PAINT MONO (-5550 1650);
DISPLAY INVISIBLE (-5550 1650);
FORCEPROP 1 LAST BODY_TYPE PLUMBING
J 2
(-5550 1700);
DISPLAY 1.446809 (-5550 1700);
PAINT GREEN (-5550 1700);
DISPLAY INVISIBLE (-5550 1700);
FORCEPROP 1 LAST HDL_TAP TRUE
J 2
(-5875 1525);
DISPLAY 1.446809 (-5875 1525);
PAINT GREEN (-5875 1525);
DISPLAY INVISIBLE (-5875 1525);
FORCEPROP 1 LAST PATH I19
J 2
(-5548 1650);
DISPLAY 0.872340 (-5548 1650);
PAINT GREEN (-5548 1650);
DISPLAY INVISIBLE (-5548 1650);
FORCEADD TAP..1
R 2
(-5825 1850);
FORCEPROP 3 LASTPIN (-5775 1850) SIG_NAME P3E_CPU0_PE1_SS_RXP<0>
J 0
(-5765 1860);
DISPLAY 0.659574 (-5765 1860);
PAINT MONO (-5765 1860);
DISPLAY INVISIBLE (-5765 1860);
FORCEPROP 1 LASTPIN (-5775 1850) BN 0
J 2
(-5763 1858);
DISPLAY 0.617021 (-5763 1858);
PAINT PINK (-5763 1858);
FORCEPROP 2 LAST CDS_LIB mstr_standard
J 0
(-5825 1850);
PAINT MONO (-5825 1850);
DISPLAY INVISIBLE (-5825 1850);
FORCEPROP 1 LAST BODY_TYPE PLUMBING
J 2
(-5825 1900);
DISPLAY 1.446809 (-5825 1900);
PAINT GREEN (-5825 1900);
DISPLAY INVISIBLE (-5825 1900);
FORCEPROP 1 LAST HDL_TAP TRUE
J 2
(-6150 1725);
DISPLAY 1.446809 (-6150 1725);
PAINT GREEN (-6150 1725);
DISPLAY INVISIBLE (-6150 1725);
FORCEPROP 1 LAST PATH I2
J 2
(-5823 1850);
DISPLAY 0.872340 (-5823 1850);
PAINT GREEN (-5823 1850);
DISPLAY INVISIBLE (-5823 1850);
FORCEADD TAP..1
R 2
(-5550 1600);
FORCEPROP 3 LASTPIN (-5500 1600) SIG_NAME P3E_CPU0_PE1_SS_RXN<0>
J 0
(-5490 1610);
DISPLAY 0.659574 (-5490 1610);
PAINT MONO (-5490 1610);
DISPLAY INVISIBLE (-5490 1610);
FORCEPROP 1 LASTPIN (-5500 1600) BN 0
J 2
(-5488 1608);
DISPLAY 0.617021 (-5488 1608);
PAINT PINK (-5488 1608);
FORCEPROP 2 LAST CDS_LIB mstr_standard
J 0
(-5550 1600);
PAINT MONO (-5550 1600);
DISPLAY INVISIBLE (-5550 1600);
FORCEPROP 1 LAST BODY_TYPE PLUMBING
J 2
(-5550 1650);
DISPLAY 1.446809 (-5550 1650);
PAINT GREEN (-5550 1650);
DISPLAY INVISIBLE (-5550 1650);
FORCEPROP 1 LAST HDL_TAP TRUE
J 2
(-5875 1475);
DISPLAY 1.446809 (-5875 1475);
PAINT GREEN (-5875 1475);
DISPLAY INVISIBLE (-5875 1475);
FORCEPROP 1 LAST PATH I20
J 2
(-5548 1600);
DISPLAY 0.872340 (-5548 1600);
PAINT GREEN (-5548 1600);
DISPLAY INVISIBLE (-5548 1600);
FORCEADD TAP..1
R 2
(-5550 1750);
FORCEPROP 3 LASTPIN (-5500 1750) SIG_NAME P3E_CPU0_PE1_SS_RXN<3>
J 0
(-5490 1760);
DISPLAY 0.659574 (-5490 1760);
PAINT MONO (-5490 1760);
DISPLAY INVISIBLE (-5490 1760);
FORCEPROP 1 LASTPIN (-5500 1750) BN 3
J 2
(-5488 1758);
DISPLAY 0.617021 (-5488 1758);
PAINT PINK (-5488 1758);
FORCEPROP 2 LAST CDS_LIB mstr_standard
J 0
(-5550 1750);
PAINT MONO (-5550 1750);
DISPLAY INVISIBLE (-5550 1750);
FORCEPROP 1 LAST BODY_TYPE PLUMBING
J 2
(-5550 1800);
DISPLAY 1.446809 (-5550 1800);
PAINT GREEN (-5550 1800);
DISPLAY INVISIBLE (-5550 1800);
FORCEPROP 1 LAST HDL_TAP TRUE
J 2
(-5875 1625);
DISPLAY 1.446809 (-5875 1625);
PAINT GREEN (-5875 1625);
DISPLAY INVISIBLE (-5875 1625);
FORCEPROP 1 LAST PATH I21
J 2
(-5548 1750);
DISPLAY 0.872340 (-5548 1750);
PAINT GREEN (-5548 1750);
DISPLAY INVISIBLE (-5548 1750);
FORCEADD TAP..1
R 2
(-5550 1700);
FORCEPROP 3 LASTPIN (-5500 1700) SIG_NAME P3E_CPU0_PE1_SS_RXN<2>
J 0
(-5490 1710);
DISPLAY 0.659574 (-5490 1710);
PAINT MONO (-5490 1710);
DISPLAY INVISIBLE (-5490 1710);
FORCEPROP 1 LASTPIN (-5500 1700) BN 2
J 2
(-5488 1708);
DISPLAY 0.617021 (-5488 1708);
PAINT PINK (-5488 1708);
FORCEPROP 2 LAST CDS_LIB mstr_standard
J 0
(-5550 1700);
PAINT MONO (-5550 1700);
DISPLAY INVISIBLE (-5550 1700);
FORCEPROP 1 LAST BODY_TYPE PLUMBING
J 2
(-5550 1750);
DISPLAY 1.446809 (-5550 1750);
PAINT GREEN (-5550 1750);
DISPLAY INVISIBLE (-5550 1750);
FORCEPROP 1 LAST HDL_TAP TRUE
J 2
(-5875 1575);
DISPLAY 1.446809 (-5875 1575);
PAINT GREEN (-5875 1575);
DISPLAY INVISIBLE (-5875 1575);
FORCEPROP 1 LAST PATH I22
J 2
(-5548 1700);
DISPLAY 0.872340 (-5548 1700);
PAINT GREEN (-5548 1700);
DISPLAY INVISIBLE (-5548 1700);
FORCEADD TAP..1
R 2
(-5550 2150);
FORCEPROP 3 LASTPIN (-5500 2150) SIG_NAME P3E_CPU0_PE1_SS_RXN<5>
J 0
(-5490 2160);
DISPLAY 0.659574 (-5490 2160);
PAINT MONO (-5490 2160);
DISPLAY INVISIBLE (-5490 2160);
FORCEPROP 1 LASTPIN (-5500 2150) BN 5
J 2
(-5488 2158);
DISPLAY 0.617021 (-5488 2158);
PAINT PINK (-5488 2158);
FORCEPROP 2 LAST CDS_LIB mstr_standard
J 0
(-5550 2150);
PAINT MONO (-5550 2150);
DISPLAY INVISIBLE (-5550 2150);
FORCEPROP 1 LAST BODY_TYPE PLUMBING
J 2
(-5550 2200);
DISPLAY 1.446809 (-5550 2200);
PAINT GREEN (-5550 2200);
DISPLAY INVISIBLE (-5550 2200);
FORCEPROP 1 LAST HDL_TAP TRUE
J 2
(-5875 2025);
DISPLAY 1.446809 (-5875 2025);
PAINT GREEN (-5875 2025);
DISPLAY INVISIBLE (-5875 2025);
FORCEPROP 1 LAST PATH I24
J 2
(-5548 2150);
DISPLAY 0.872340 (-5548 2150);
PAINT GREEN (-5548 2150);
DISPLAY INVISIBLE (-5548 2150);
FORCEADD TAP..1
R 2
(-5550 2200);
FORCEPROP 3 LASTPIN (-5500 2200) SIG_NAME P3E_CPU0_PE1_SS_RXN<6>
J 0
(-5490 2210);
DISPLAY 0.659574 (-5490 2210);
PAINT MONO (-5490 2210);
DISPLAY INVISIBLE (-5490 2210);
FORCEPROP 1 LASTPIN (-5500 2200) BN 6
J 2
(-5488 2208);
DISPLAY 0.617021 (-5488 2208);
PAINT PINK (-5488 2208);
FORCEPROP 2 LAST CDS_LIB mstr_standard
J 0
(-5550 2200);
PAINT MONO (-5550 2200);
DISPLAY INVISIBLE (-5550 2200);
FORCEPROP 1 LAST BODY_TYPE PLUMBING
J 2
(-5550 2250);
DISPLAY 1.446809 (-5550 2250);
PAINT GREEN (-5550 2250);
DISPLAY INVISIBLE (-5550 2250);
FORCEPROP 1 LAST HDL_TAP TRUE
J 2
(-5875 2075);
DISPLAY 1.446809 (-5875 2075);
PAINT GREEN (-5875 2075);
DISPLAY INVISIBLE (-5875 2075);
FORCEPROP 1 LAST PATH I25
J 2
(-5548 2200);
DISPLAY 0.872340 (-5548 2200);
PAINT GREEN (-5548 2200);
DISPLAY INVISIBLE (-5548 2200);
FORCEADD TAP..1
R 2
(-5550 2100);
FORCEPROP 3 LASTPIN (-5500 2100) SIG_NAME P3E_CPU0_PE1_SS_RXN<4>
J 0
(-5490 2110);
DISPLAY 0.659574 (-5490 2110);
PAINT MONO (-5490 2110);
DISPLAY INVISIBLE (-5490 2110);
FORCEPROP 1 LASTPIN (-5500 2100) BN 4
J 2
(-5488 2108);
DISPLAY 0.617021 (-5488 2108);
PAINT PINK (-5488 2108);
FORCEPROP 2 LAST CDS_LIB mstr_standard
J 0
(-5550 2100);
PAINT MONO (-5550 2100);
DISPLAY INVISIBLE (-5550 2100);
FORCEPROP 1 LAST BODY_TYPE PLUMBING
J 2
(-5550 2150);
DISPLAY 1.446809 (-5550 2150);
PAINT GREEN (-5550 2150);
DISPLAY INVISIBLE (-5550 2150);
FORCEPROP 1 LAST HDL_TAP TRUE
J 2
(-5875 1975);
DISPLAY 1.446809 (-5875 1975);
PAINT GREEN (-5875 1975);
DISPLAY INVISIBLE (-5875 1975);
FORCEPROP 1 LAST PATH I26
J 2
(-5548 2100);
DISPLAY 0.872340 (-5548 2100);
PAINT GREEN (-5548 2100);
DISPLAY INVISIBLE (-5548 2100);
FORCEADD TAP..1
R 2
(-5550 2250);
FORCEPROP 3 LASTPIN (-5500 2250) SIG_NAME P3E_CPU0_PE1_SS_RXN<7>
J 0
(-5490 2260);
DISPLAY 0.659574 (-5490 2260);
PAINT MONO (-5490 2260);
DISPLAY INVISIBLE (-5490 2260);
FORCEPROP 1 LASTPIN (-5500 2250) BN 7
J 2
(-5488 2258);
DISPLAY 0.617021 (-5488 2258);
PAINT PINK (-5488 2258);
FORCEPROP 2 LAST CDS_LIB mstr_standard
J 0
(-5550 2250);
PAINT MONO (-5550 2250);
DISPLAY INVISIBLE (-5550 2250);
FORCEPROP 1 LAST BODY_TYPE PLUMBING
J 2
(-5550 2300);
DISPLAY 1.446809 (-5550 2300);
PAINT GREEN (-5550 2300);
DISPLAY INVISIBLE (-5550 2300);
FORCEPROP 1 LAST HDL_TAP TRUE
J 2
(-5875 2125);
DISPLAY 1.446809 (-5875 2125);
PAINT GREEN (-5875 2125);
DISPLAY INVISIBLE (-5875 2125);
FORCEPROP 1 LAST PATH I27
J 2
(-5548 2250);
DISPLAY 0.872340 (-5548 2250);
PAINT GREEN (-5548 2250);
DISPLAY INVISIBLE (-5548 2250);
FORCEADD TAP..1
R 2
(-5550 2600);
FORCEPROP 3 LASTPIN (-5500 2600) SIG_NAME P3E_CPU0_PE1_PCH_RXN<8>
J 0
(-5490 2610);
DISPLAY 0.659574 (-5490 2610);
PAINT MONO (-5490 2610);
DISPLAY INVISIBLE (-5490 2610);
FORCEPROP 1 LASTPIN (-5500 2600) BN 8
J 2
(-5488 2608);
DISPLAY 0.617021 (-5488 2608);
PAINT PINK (-5488 2608);
FORCEPROP 2 LAST CDS_LIB mstr_standard
J 0
(-5550 2600);
PAINT MONO (-5550 2600);
DISPLAY INVISIBLE (-5550 2600);
FORCEPROP 1 LAST BODY_TYPE PLUMBING
J 2
(-5550 2650);
DISPLAY 1.446809 (-5550 2650);
PAINT GREEN (-5550 2650);
DISPLAY INVISIBLE (-5550 2650);
FORCEPROP 1 LAST HDL_TAP TRUE
J 2
(-5875 2475);
DISPLAY 1.446809 (-5875 2475);
PAINT GREEN (-5875 2475);
DISPLAY INVISIBLE (-5875 2475);
FORCEPROP 1 LAST PATH I28
J 2
(-5548 2600);
DISPLAY 0.872340 (-5548 2600);
PAINT GREEN (-5548 2600);
DISPLAY INVISIBLE (-5548 2600);
FORCEADD TAP..1
R 2
(-5550 2650);
FORCEPROP 3 LASTPIN (-5500 2650) SIG_NAME P3E_CPU0_PE1_PCH_RXN<9>
J 0
(-5490 2660);
DISPLAY 0.659574 (-5490 2660);
PAINT MONO (-5490 2660);
DISPLAY INVISIBLE (-5490 2660);
FORCEPROP 1 LASTPIN (-5500 2650) BN 9
J 2
(-5488 2658);
DISPLAY 0.617021 (-5488 2658);
PAINT PINK (-5488 2658);
FORCEPROP 2 LAST CDS_LIB mstr_standard
J 0
(-5550 2650);
PAINT MONO (-5550 2650);
DISPLAY INVISIBLE (-5550 2650);
FORCEPROP 1 LAST BODY_TYPE PLUMBING
J 2
(-5550 2700);
DISPLAY 1.446809 (-5550 2700);
PAINT GREEN (-5550 2700);
DISPLAY INVISIBLE (-5550 2700);
FORCEPROP 1 LAST HDL_TAP TRUE
J 2
(-5875 2525);
DISPLAY 1.446809 (-5875 2525);
PAINT GREEN (-5875 2525);
DISPLAY INVISIBLE (-5875 2525);
FORCEPROP 1 LAST PATH I29
J 2
(-5548 2650);
DISPLAY 0.872340 (-5548 2650);
PAINT GREEN (-5548 2650);
DISPLAY INVISIBLE (-5548 2650);
FORCEADD TAP..1
R 2
(-5825 1950);
FORCEPROP 3 LASTPIN (-5775 1950) SIG_NAME P3E_CPU0_PE1_SS_RXP<2>
J 0
(-5765 1960);
DISPLAY 0.659574 (-5765 1960);
PAINT MONO (-5765 1960);
DISPLAY INVISIBLE (-5765 1960);
FORCEPROP 1 LASTPIN (-5775 1950) BN 2
J 2
(-5763 1958);
DISPLAY 0.617021 (-5763 1958);
PAINT PINK (-5763 1958);
FORCEPROP 2 LAST CDS_LIB mstr_standard
J 0
(-5825 1950);
PAINT MONO (-5825 1950);
DISPLAY INVISIBLE (-5825 1950);
FORCEPROP 1 LAST BODY_TYPE PLUMBING
J 2
(-5825 2000);
DISPLAY 1.446809 (-5825 2000);
PAINT GREEN (-5825 2000);
DISPLAY INVISIBLE (-5825 2000);
FORCEPROP 1 LAST HDL_TAP TRUE
J 2
(-6150 1825);
DISPLAY 1.446809 (-6150 1825);
PAINT GREEN (-6150 1825);
DISPLAY INVISIBLE (-6150 1825);
FORCEPROP 1 LAST PATH I3
J 2
(-5823 1950);
DISPLAY 0.872340 (-5823 1950);
PAINT GREEN (-5823 1950);
DISPLAY INVISIBLE (-5823 1950);
FORCEADD TAP..1
R 2
(-5550 2700);
FORCEPROP 3 LASTPIN (-5500 2700) SIG_NAME P3E_CPU0_PE1_PCH_RXN<10>
J 0
(-5490 2710);
DISPLAY 0.659574 (-5490 2710);
PAINT MONO (-5490 2710);
DISPLAY INVISIBLE (-5490 2710);
FORCEPROP 1 LASTPIN (-5500 2700) BN 10
J 2
(-5488 2708);
DISPLAY 0.617021 (-5488 2708);
PAINT PINK (-5488 2708);
FORCEPROP 2 LAST CDS_LIB mstr_standard
J 0
(-5550 2700);
PAINT MONO (-5550 2700);
DISPLAY INVISIBLE (-5550 2700);
FORCEPROP 1 LAST BODY_TYPE PLUMBING
J 2
(-5550 2750);
DISPLAY 1.446809 (-5550 2750);
PAINT GREEN (-5550 2750);
DISPLAY INVISIBLE (-5550 2750);
FORCEPROP 1 LAST HDL_TAP TRUE
J 2
(-5875 2575);
DISPLAY 1.446809 (-5875 2575);
PAINT GREEN (-5875 2575);
DISPLAY INVISIBLE (-5875 2575);
FORCEPROP 1 LAST PATH I30
J 2
(-5548 2700);
DISPLAY 0.872340 (-5548 2700);
PAINT GREEN (-5548 2700);
DISPLAY INVISIBLE (-5548 2700);
FORCEADD TAP..1
R 2
(-5550 2750);
FORCEPROP 3 LASTPIN (-5500 2750) SIG_NAME P3E_CPU0_PE1_PCH_RXN<11>
J 0
(-5490 2760);
DISPLAY 0.659574 (-5490 2760);
PAINT MONO (-5490 2760);
DISPLAY INVISIBLE (-5490 2760);
FORCEPROP 1 LASTPIN (-5500 2750) BN 11
J 2
(-5488 2758);
DISPLAY 0.617021 (-5488 2758);
PAINT PINK (-5488 2758);
FORCEPROP 2 LAST CDS_LIB mstr_standard
J 0
(-5550 2750);
PAINT MONO (-5550 2750);
DISPLAY INVISIBLE (-5550 2750);
FORCEPROP 1 LAST BODY_TYPE PLUMBING
J 2
(-5550 2800);
DISPLAY 1.446809 (-5550 2800);
PAINT GREEN (-5550 2800);
DISPLAY INVISIBLE (-5550 2800);
FORCEPROP 1 LAST HDL_TAP TRUE
J 2
(-5875 2625);
DISPLAY 1.446809 (-5875 2625);
PAINT GREEN (-5875 2625);
DISPLAY INVISIBLE (-5875 2625);
FORCEPROP 1 LAST PATH I31
J 2
(-5548 2750);
DISPLAY 0.872340 (-5548 2750);
PAINT GREEN (-5548 2750);
DISPLAY INVISIBLE (-5548 2750);
FORCEADD TAP..1
R 2
(-5550 3150);
FORCEPROP 3 LASTPIN (-5500 3150) SIG_NAME P3E_CPU0_PE1_PCH_RXN<13>
J 0
(-5490 3160);
DISPLAY 0.659574 (-5490 3160);
PAINT MONO (-5490 3160);
DISPLAY INVISIBLE (-5490 3160);
FORCEPROP 1 LASTPIN (-5500 3150) BN 13
J 2
(-5488 3158);
DISPLAY 0.617021 (-5488 3158);
PAINT PINK (-5488 3158);
FORCEPROP 2 LAST CDS_LIB mstr_standard
J 0
(-5550 3150);
PAINT MONO (-5550 3150);
DISPLAY INVISIBLE (-5550 3150);
FORCEPROP 1 LAST BODY_TYPE PLUMBING
J 2
(-5550 3200);
DISPLAY 1.446809 (-5550 3200);
PAINT GREEN (-5550 3200);
DISPLAY INVISIBLE (-5550 3200);
FORCEPROP 1 LAST HDL_TAP TRUE
J 2
(-5875 3025);
DISPLAY 1.446809 (-5875 3025);
PAINT GREEN (-5875 3025);
DISPLAY INVISIBLE (-5875 3025);
FORCEPROP 1 LAST PATH I32
J 2
(-5548 3150);
DISPLAY 0.872340 (-5548 3150);
PAINT GREEN (-5548 3150);
DISPLAY INVISIBLE (-5548 3150);
FORCEADD TAP..1
R 2
(-5550 3100);
FORCEPROP 3 LASTPIN (-5500 3100) SIG_NAME P3E_CPU0_PE1_PCH_RXN<12>
J 0
(-5490 3110);
DISPLAY 0.659574 (-5490 3110);
PAINT MONO (-5490 3110);
DISPLAY INVISIBLE (-5490 3110);
FORCEPROP 1 LASTPIN (-5500 3100) BN 12
J 2
(-5488 3108);
DISPLAY 0.617021 (-5488 3108);
PAINT PINK (-5488 3108);
FORCEPROP 2 LAST CDS_LIB mstr_standard
J 0
(-5550 3100);
PAINT MONO (-5550 3100);
DISPLAY INVISIBLE (-5550 3100);
FORCEPROP 1 LAST BODY_TYPE PLUMBING
J 2
(-5550 3150);
DISPLAY 1.446809 (-5550 3150);
PAINT GREEN (-5550 3150);
DISPLAY INVISIBLE (-5550 3150);
FORCEPROP 1 LAST HDL_TAP TRUE
J 2
(-5875 2975);
DISPLAY 1.446809 (-5875 2975);
PAINT GREEN (-5875 2975);
DISPLAY INVISIBLE (-5875 2975);
FORCEPROP 1 LAST PATH I33
J 2
(-5548 3100);
DISPLAY 0.872340 (-5548 3100);
PAINT GREEN (-5548 3100);
DISPLAY INVISIBLE (-5548 3100);
FORCEADD TAP..1
R 2
(-5550 3200);
FORCEPROP 3 LASTPIN (-5500 3200) SIG_NAME P3E_CPU0_PE1_PCH_RXN<14>
J 0
(-5490 3210);
DISPLAY 0.659574 (-5490 3210);
PAINT MONO (-5490 3210);
DISPLAY INVISIBLE (-5490 3210);
FORCEPROP 1 LASTPIN (-5500 3200) BN 14
J 2
(-5488 3208);
DISPLAY 0.617021 (-5488 3208);
PAINT PINK (-5488 3208);
FORCEPROP 2 LAST CDS_LIB mstr_standard
J 0
(-5550 3200);
PAINT MONO (-5550 3200);
DISPLAY INVISIBLE (-5550 3200);
FORCEPROP 1 LAST BODY_TYPE PLUMBING
J 2
(-5550 3250);
DISPLAY 1.446809 (-5550 3250);
PAINT GREEN (-5550 3250);
DISPLAY INVISIBLE (-5550 3250);
FORCEPROP 1 LAST HDL_TAP TRUE
J 2
(-5875 3075);
DISPLAY 1.446809 (-5875 3075);
PAINT GREEN (-5875 3075);
DISPLAY INVISIBLE (-5875 3075);
FORCEPROP 1 LAST PATH I34
J 2
(-5548 3200);
DISPLAY 0.872340 (-5548 3200);
PAINT GREEN (-5548 3200);
DISPLAY INVISIBLE (-5548 3200);
FORCEADD TAP..1
R 2
(-5550 3250);
FORCEPROP 3 LASTPIN (-5500 3250) SIG_NAME P3E_CPU0_PE1_PCH_RXN<15>
J 0
(-5490 3260);
DISPLAY 0.659574 (-5490 3260);
PAINT MONO (-5490 3260);
DISPLAY INVISIBLE (-5490 3260);
FORCEPROP 1 LASTPIN (-5500 3250) BN 15
J 2
(-5488 3258);
DISPLAY 0.617021 (-5488 3258);
PAINT PINK (-5488 3258);
FORCEPROP 2 LAST CDS_LIB mstr_standard
J 0
(-5550 3250);
PAINT MONO (-5550 3250);
DISPLAY INVISIBLE (-5550 3250);
FORCEPROP 1 LAST BODY_TYPE PLUMBING
J 2
(-5550 3300);
DISPLAY 1.446809 (-5550 3300);
PAINT GREEN (-5550 3300);
DISPLAY INVISIBLE (-5550 3300);
FORCEPROP 1 LAST HDL_TAP TRUE
J 2
(-5875 3125);
DISPLAY 1.446809 (-5875 3125);
PAINT GREEN (-5875 3125);
DISPLAY INVISIBLE (-5875 3125);
FORCEPROP 1 LAST PATH I35
J 2
(-5548 3250);
DISPLAY 0.872340 (-5548 3250);
PAINT GREEN (-5548 3250);
DISPLAY INVISIBLE (-5548 3250);
FORCEADD TAP..1
(-2625 1600);
FORCEPROP 3 LASTPIN (-2675 1600) SIG_NAME P3E_CPU0_PE1_SS_TXN<0>
J 0
(-2665 1610);
DISPLAY 0.659574 (-2665 1610);
PAINT MONO (-2665 1610);
DISPLAY INVISIBLE (-2665 1610);
FORCEPROP 1 LASTPIN (-2675 1600) BN 0
J 0
(-2687 1608);
DISPLAY 0.617021 (-2687 1608);
PAINT PINK (-2687 1608);
FORCEPROP 2 LAST CDS_LIB mstr_standard
J 2
(-2625 1600);
PAINT MONO (-2625 1600);
DISPLAY INVISIBLE (-2625 1600);
FORCEPROP 1 LAST BODY_TYPE PLUMBING
J 0
(-2625 1650);
DISPLAY 1.446809 (-2625 1650);
PAINT GREEN (-2625 1650);
DISPLAY INVISIBLE (-2625 1650);
FORCEPROP 1 LAST HDL_TAP TRUE
J 0
(-2300 1475);
DISPLAY 1.446809 (-2300 1475);
PAINT GREEN (-2300 1475);
DISPLAY INVISIBLE (-2300 1475);
FORCEPROP 1 LAST PATH I36
J 0
(-2627 1600);
DISPLAY 0.872340 (-2627 1600);
PAINT GREEN (-2627 1600);
DISPLAY INVISIBLE (-2627 1600);
FORCEADD TAP..1
(-2625 1650);
FORCEPROP 3 LASTPIN (-2675 1650) SIG_NAME P3E_CPU0_PE1_SS_TXN<1>
J 0
(-2665 1660);
DISPLAY 0.659574 (-2665 1660);
PAINT MONO (-2665 1660);
DISPLAY INVISIBLE (-2665 1660);
FORCEPROP 1 LASTPIN (-2675 1650) BN 1
J 0
(-2687 1658);
DISPLAY 0.617021 (-2687 1658);
PAINT PINK (-2687 1658);
FORCEPROP 2 LAST CDS_LIB mstr_standard
J 2
(-2625 1650);
PAINT MONO (-2625 1650);
DISPLAY INVISIBLE (-2625 1650);
FORCEPROP 1 LAST BODY_TYPE PLUMBING
J 0
(-2625 1700);
DISPLAY 1.446809 (-2625 1700);
PAINT GREEN (-2625 1700);
DISPLAY INVISIBLE (-2625 1700);
FORCEPROP 1 LAST HDL_TAP TRUE
J 0
(-2300 1525);
DISPLAY 1.446809 (-2300 1525);
PAINT GREEN (-2300 1525);
DISPLAY INVISIBLE (-2300 1525);
FORCEPROP 1 LAST PATH I37
J 0
(-2627 1650);
DISPLAY 0.872340 (-2627 1650);
PAINT GREEN (-2627 1650);
DISPLAY INVISIBLE (-2627 1650);
FORCEADD TAP..1
(-2625 1700);
FORCEPROP 3 LASTPIN (-2675 1700) SIG_NAME P3E_CPU0_PE1_SS_TXN<2>
J 0
(-2665 1710);
DISPLAY 0.659574 (-2665 1710);
PAINT MONO (-2665 1710);
DISPLAY INVISIBLE (-2665 1710);
FORCEPROP 1 LASTPIN (-2675 1700) BN 2
J 0
(-2687 1708);
DISPLAY 0.617021 (-2687 1708);
PAINT PINK (-2687 1708);
FORCEPROP 2 LAST CDS_LIB mstr_standard
J 2
(-2625 1700);
PAINT MONO (-2625 1700);
DISPLAY INVISIBLE (-2625 1700);
FORCEPROP 1 LAST BODY_TYPE PLUMBING
J 0
(-2625 1750);
DISPLAY 1.446809 (-2625 1750);
PAINT GREEN (-2625 1750);
DISPLAY INVISIBLE (-2625 1750);
FORCEPROP 1 LAST HDL_TAP TRUE
J 0
(-2300 1575);
DISPLAY 1.446809 (-2300 1575);
PAINT GREEN (-2300 1575);
DISPLAY INVISIBLE (-2300 1575);
FORCEPROP 1 LAST PATH I38
J 0
(-2627 1700);
DISPLAY 0.872340 (-2627 1700);
PAINT GREEN (-2627 1700);
DISPLAY INVISIBLE (-2627 1700);
FORCEADD TAP..1
(-2625 1750);
FORCEPROP 3 LASTPIN (-2675 1750) SIG_NAME P3E_CPU0_PE1_SS_TXN<3>
J 0
(-2665 1760);
DISPLAY 0.659574 (-2665 1760);
PAINT MONO (-2665 1760);
DISPLAY INVISIBLE (-2665 1760);
FORCEPROP 1 LASTPIN (-2675 1750) BN 3
J 0
(-2687 1758);
DISPLAY 0.617021 (-2687 1758);
PAINT PINK (-2687 1758);
FORCEPROP 2 LAST CDS_LIB mstr_standard
J 2
(-2625 1750);
PAINT MONO (-2625 1750);
DISPLAY INVISIBLE (-2625 1750);
FORCEPROP 1 LAST BODY_TYPE PLUMBING
J 0
(-2625 1800);
DISPLAY 1.446809 (-2625 1800);
PAINT GREEN (-2625 1800);
DISPLAY INVISIBLE (-2625 1800);
FORCEPROP 1 LAST HDL_TAP TRUE
J 0
(-2300 1625);
DISPLAY 1.446809 (-2300 1625);
PAINT GREEN (-2300 1625);
DISPLAY INVISIBLE (-2300 1625);
FORCEPROP 1 LAST PATH I39
J 0
(-2627 1750);
DISPLAY 0.872340 (-2627 1750);
PAINT GREEN (-2627 1750);
DISPLAY INVISIBLE (-2627 1750);
FORCEADD TAP..1
(-2175 1850);
FORCEPROP 3 LASTPIN (-2225 1850) SIG_NAME P3E_CPU0_PE1_SS_TXP<0>
J 0
(-2215 1860);
DISPLAY 0.659574 (-2215 1860);
PAINT MONO (-2215 1860);
DISPLAY INVISIBLE (-2215 1860);
FORCEPROP 1 LASTPIN (-2225 1850) BN 0
J 0
(-2237 1858);
DISPLAY 0.617021 (-2237 1858);
PAINT PINK (-2237 1858);
FORCEPROP 2 LAST CDS_LIB mstr_standard
J 2
(-2175 1850);
PAINT MONO (-2175 1850);
DISPLAY INVISIBLE (-2175 1850);
FORCEPROP 1 LAST BODY_TYPE PLUMBING
J 0
(-2175 1900);
DISPLAY 1.446809 (-2175 1900);
PAINT GREEN (-2175 1900);
DISPLAY INVISIBLE (-2175 1900);
FORCEPROP 1 LAST HDL_TAP TRUE
J 0
(-1850 1725);
DISPLAY 1.446809 (-1850 1725);
PAINT GREEN (-1850 1725);
DISPLAY INVISIBLE (-1850 1725);
FORCEPROP 1 LAST PATH I40
J 0
(-2177 1850);
DISPLAY 0.872340 (-2177 1850);
PAINT GREEN (-2177 1850);
DISPLAY INVISIBLE (-2177 1850);
FORCEADD TAP..1
(-2175 1900);
FORCEPROP 3 LASTPIN (-2225 1900) SIG_NAME P3E_CPU0_PE1_SS_TXP<1>
J 0
(-2215 1910);
DISPLAY 0.659574 (-2215 1910);
PAINT MONO (-2215 1910);
DISPLAY INVISIBLE (-2215 1910);
FORCEPROP 1 LASTPIN (-2225 1900) BN 1
J 0
(-2237 1908);
DISPLAY 0.617021 (-2237 1908);
PAINT PINK (-2237 1908);
FORCEPROP 2 LAST CDS_LIB mstr_standard
J 2
(-2175 1900);
PAINT MONO (-2175 1900);
DISPLAY INVISIBLE (-2175 1900);
FORCEPROP 1 LAST BODY_TYPE PLUMBING
J 0
(-2175 1950);
DISPLAY 1.446809 (-2175 1950);
PAINT GREEN (-2175 1950);
DISPLAY INVISIBLE (-2175 1950);
FORCEPROP 1 LAST HDL_TAP TRUE
J 0
(-1850 1775);
DISPLAY 1.446809 (-1850 1775);
PAINT GREEN (-1850 1775);
DISPLAY INVISIBLE (-1850 1775);
FORCEPROP 1 LAST PATH I41
J 0
(-2177 1900);
DISPLAY 0.872340 (-2177 1900);
PAINT GREEN (-2177 1900);
DISPLAY INVISIBLE (-2177 1900);
FORCEADD TAP..1
(-2175 1950);
FORCEPROP 3 LASTPIN (-2225 1950) SIG_NAME P3E_CPU0_PE1_SS_TXP<2>
J 0
(-2215 1960);
DISPLAY 0.659574 (-2215 1960);
PAINT MONO (-2215 1960);
DISPLAY INVISIBLE (-2215 1960);
FORCEPROP 1 LASTPIN (-2225 1950) BN 2
J 0
(-2237 1958);
DISPLAY 0.617021 (-2237 1958);
PAINT PINK (-2237 1958);
FORCEPROP 2 LAST CDS_LIB mstr_standard
J 2
(-2175 1950);
PAINT MONO (-2175 1950);
DISPLAY INVISIBLE (-2175 1950);
FORCEPROP 1 LAST BODY_TYPE PLUMBING
J 0
(-2175 2000);
DISPLAY 1.446809 (-2175 2000);
PAINT GREEN (-2175 2000);
DISPLAY INVISIBLE (-2175 2000);
FORCEPROP 1 LAST HDL_TAP TRUE
J 0
(-1850 1825);
DISPLAY 1.446809 (-1850 1825);
PAINT GREEN (-1850 1825);
DISPLAY INVISIBLE (-1850 1825);
FORCEPROP 1 LAST PATH I42
J 0
(-2177 1950);
DISPLAY 0.872340 (-2177 1950);
PAINT GREEN (-2177 1950);
DISPLAY INVISIBLE (-2177 1950);
FORCEADD TAP..1
(-2625 2100);
FORCEPROP 3 LASTPIN (-2675 2100) SIG_NAME P3E_CPU0_PE1_SS_TXN<4>
J 0
(-2665 2110);
DISPLAY 0.659574 (-2665 2110);
PAINT MONO (-2665 2110);
DISPLAY INVISIBLE (-2665 2110);
FORCEPROP 1 LASTPIN (-2675 2100) BN 4
J 0
(-2687 2108);
DISPLAY 0.617021 (-2687 2108);
PAINT PINK (-2687 2108);
FORCEPROP 2 LAST CDS_LIB mstr_standard
J 0
(-2625 2100);
PAINT MONO (-2625 2100);
DISPLAY INVISIBLE (-2625 2100);
FORCEPROP 1 LAST BODY_TYPE PLUMBING
J 0
(-2625 2150);
DISPLAY 1.446809 (-2625 2150);
PAINT GREEN (-2625 2150);
DISPLAY INVISIBLE (-2625 2150);
FORCEPROP 1 LAST HDL_TAP TRUE
J 0
(-2300 1975);
DISPLAY 1.446809 (-2300 1975);
PAINT GREEN (-2300 1975);
DISPLAY INVISIBLE (-2300 1975);
FORCEPROP 1 LAST PATH I43
J 0
(-2627 2100);
DISPLAY 0.872340 (-2627 2100);
PAINT GREEN (-2627 2100);
DISPLAY INVISIBLE (-2627 2100);
FORCEADD TAP..1
(-2625 2150);
FORCEPROP 3 LASTPIN (-2675 2150) SIG_NAME P3E_CPU0_PE1_SS_TXN<5>
J 0
(-2665 2160);
DISPLAY 0.659574 (-2665 2160);
PAINT MONO (-2665 2160);
DISPLAY INVISIBLE (-2665 2160);
FORCEPROP 1 LASTPIN (-2675 2150) BN 5
J 0
(-2687 2158);
DISPLAY 0.617021 (-2687 2158);
PAINT PINK (-2687 2158);
FORCEPROP 2 LAST CDS_LIB mstr_standard
J 0
(-2625 2150);
PAINT MONO (-2625 2150);
DISPLAY INVISIBLE (-2625 2150);
FORCEPROP 1 LAST BODY_TYPE PLUMBING
J 0
(-2625 2200);
DISPLAY 1.446809 (-2625 2200);
PAINT GREEN (-2625 2200);
DISPLAY INVISIBLE (-2625 2200);
FORCEPROP 1 LAST HDL_TAP TRUE
J 0
(-2300 2025);
DISPLAY 1.446809 (-2300 2025);
PAINT GREEN (-2300 2025);
DISPLAY INVISIBLE (-2300 2025);
FORCEPROP 1 LAST PATH I44
J 0
(-2627 2150);
DISPLAY 0.872340 (-2627 2150);
PAINT GREEN (-2627 2150);
DISPLAY INVISIBLE (-2627 2150);
FORCEADD TAP..1
(-2625 2200);
FORCEPROP 3 LASTPIN (-2675 2200) SIG_NAME P3E_CPU0_PE1_SS_TXN<6>
J 0
(-2665 2210);
DISPLAY 0.659574 (-2665 2210);
PAINT MONO (-2665 2210);
DISPLAY INVISIBLE (-2665 2210);
FORCEPROP 1 LASTPIN (-2675 2200) BN 6
J 0
(-2687 2208);
DISPLAY 0.617021 (-2687 2208);
PAINT PINK (-2687 2208);
FORCEPROP 2 LAST CDS_LIB mstr_standard
J 0
(-2625 2200);
PAINT MONO (-2625 2200);
DISPLAY INVISIBLE (-2625 2200);
FORCEPROP 1 LAST BODY_TYPE PLUMBING
J 0
(-2625 2250);
DISPLAY 1.446809 (-2625 2250);
PAINT GREEN (-2625 2250);
DISPLAY INVISIBLE (-2625 2250);
FORCEPROP 1 LAST HDL_TAP TRUE
J 0
(-2300 2075);
DISPLAY 1.446809 (-2300 2075);
PAINT GREEN (-2300 2075);
DISPLAY INVISIBLE (-2300 2075);
FORCEPROP 1 LAST PATH I45
J 0
(-2627 2200);
DISPLAY 0.872340 (-2627 2200);
PAINT GREEN (-2627 2200);
DISPLAY INVISIBLE (-2627 2200);
FORCEADD TAP..1
(-2625 2250);
FORCEPROP 3 LASTPIN (-2675 2250) SIG_NAME P3E_CPU0_PE1_SS_TXN<7>
J 0
(-2665 2260);
DISPLAY 0.659574 (-2665 2260);
PAINT MONO (-2665 2260);
DISPLAY INVISIBLE (-2665 2260);
FORCEPROP 1 LASTPIN (-2675 2250) BN 7
J 0
(-2687 2258);
DISPLAY 0.617021 (-2687 2258);
PAINT PINK (-2687 2258);
FORCEPROP 2 LAST CDS_LIB mstr_standard
J 0
(-2625 2250);
PAINT MONO (-2625 2250);
DISPLAY INVISIBLE (-2625 2250);
FORCEPROP 1 LAST BODY_TYPE PLUMBING
J 0
(-2625 2300);
DISPLAY 1.446809 (-2625 2300);
PAINT GREEN (-2625 2300);
DISPLAY INVISIBLE (-2625 2300);
FORCEPROP 1 LAST HDL_TAP TRUE
J 0
(-2300 2125);
DISPLAY 1.446809 (-2300 2125);
PAINT GREEN (-2300 2125);
DISPLAY INVISIBLE (-2300 2125);
FORCEPROP 1 LAST PATH I46
J 0
(-2627 2250);
DISPLAY 0.872340 (-2627 2250);
PAINT GREEN (-2627 2250);
DISPLAY INVISIBLE (-2627 2250);
FORCEADD TAP..1
(-2625 2600);
FORCEPROP 3 LASTPIN (-2675 2600) SIG_NAME P3E_CPU0_PE1_PCH_TXN<8>
J 0
(-2665 2610);
DISPLAY 0.659574 (-2665 2610);
PAINT MONO (-2665 2610);
DISPLAY INVISIBLE (-2665 2610);
FORCEPROP 1 LASTPIN (-2675 2600) BN 8
J 0
(-2687 2608);
DISPLAY 0.617021 (-2687 2608);
PAINT PINK (-2687 2608);
FORCEPROP 2 LAST CDS_LIB mstr_standard
J 2
(-2625 2600);
PAINT MONO (-2625 2600);
DISPLAY INVISIBLE (-2625 2600);
FORCEPROP 1 LAST BODY_TYPE PLUMBING
J 0
(-2625 2650);
DISPLAY 1.446809 (-2625 2650);
PAINT GREEN (-2625 2650);
DISPLAY INVISIBLE (-2625 2650);
FORCEPROP 1 LAST HDL_TAP TRUE
J 0
(-2300 2475);
DISPLAY 1.446809 (-2300 2475);
PAINT GREEN (-2300 2475);
DISPLAY INVISIBLE (-2300 2475);
FORCEPROP 1 LAST PATH I47
J 0
(-2627 2600);
DISPLAY 0.872340 (-2627 2600);
PAINT GREEN (-2627 2600);
DISPLAY INVISIBLE (-2627 2600);
FORCEADD TAP..1
(-2625 2650);
FORCEPROP 3 LASTPIN (-2675 2650) SIG_NAME P3E_CPU0_PE1_PCH_TXN<9>
J 0
(-2665 2660);
DISPLAY 0.659574 (-2665 2660);
PAINT MONO (-2665 2660);
DISPLAY INVISIBLE (-2665 2660);
FORCEPROP 1 LASTPIN (-2675 2650) BN 9
J 0
(-2687 2658);
DISPLAY 0.617021 (-2687 2658);
PAINT PINK (-2687 2658);
FORCEPROP 2 LAST CDS_LIB mstr_standard
J 2
(-2625 2650);
PAINT MONO (-2625 2650);
DISPLAY INVISIBLE (-2625 2650);
FORCEPROP 1 LAST BODY_TYPE PLUMBING
J 0
(-2625 2700);
DISPLAY 1.446809 (-2625 2700);
PAINT GREEN (-2625 2700);
DISPLAY INVISIBLE (-2625 2700);
FORCEPROP 1 LAST HDL_TAP TRUE
J 0
(-2300 2525);
DISPLAY 1.446809 (-2300 2525);
PAINT GREEN (-2300 2525);
DISPLAY INVISIBLE (-2300 2525);
FORCEPROP 1 LAST PATH I48
J 0
(-2627 2650);
DISPLAY 0.872340 (-2627 2650);
PAINT GREEN (-2627 2650);
DISPLAY INVISIBLE (-2627 2650);
FORCEADD TAP..1
(-2625 2700);
FORCEPROP 3 LASTPIN (-2675 2700) SIG_NAME P3E_CPU0_PE1_PCH_TXN<10>
J 0
(-2665 2710);
DISPLAY 0.659574 (-2665 2710);
PAINT MONO (-2665 2710);
DISPLAY INVISIBLE (-2665 2710);
FORCEPROP 1 LASTPIN (-2675 2700) BN 10
J 0
(-2687 2708);
DISPLAY 0.617021 (-2687 2708);
PAINT PINK (-2687 2708);
FORCEPROP 2 LAST CDS_LIB mstr_standard
J 2
(-2625 2700);
PAINT MONO (-2625 2700);
DISPLAY INVISIBLE (-2625 2700);
FORCEPROP 1 LAST BODY_TYPE PLUMBING
J 0
(-2625 2750);
DISPLAY 1.446809 (-2625 2750);
PAINT GREEN (-2625 2750);
DISPLAY INVISIBLE (-2625 2750);
FORCEPROP 1 LAST HDL_TAP TRUE
J 0
(-2300 2575);
DISPLAY 1.446809 (-2300 2575);
PAINT GREEN (-2300 2575);
DISPLAY INVISIBLE (-2300 2575);
FORCEPROP 1 LAST PATH I49
J 0
(-2627 2700);
DISPLAY 0.872340 (-2627 2700);
PAINT GREEN (-2627 2700);
DISPLAY INVISIBLE (-2627 2700);
FORCEADD TAP..1
(-2175 2000);
FORCEPROP 3 LASTPIN (-2225 2000) SIG_NAME P3E_CPU0_PE1_SS_TXP<3>
J 0
(-2215 2010);
DISPLAY 0.659574 (-2215 2010);
PAINT MONO (-2215 2010);
DISPLAY INVISIBLE (-2215 2010);
FORCEPROP 1 LASTPIN (-2225 2000) BN 3
J 0
(-2237 2008);
DISPLAY 0.617021 (-2237 2008);
PAINT PINK (-2237 2008);
FORCEPROP 2 LAST CDS_LIB mstr_standard
J 2
(-2175 2000);
PAINT MONO (-2175 2000);
DISPLAY INVISIBLE (-2175 2000);
FORCEPROP 1 LAST BODY_TYPE PLUMBING
J 0
(-2175 2050);
DISPLAY 1.446809 (-2175 2050);
PAINT GREEN (-2175 2050);
DISPLAY INVISIBLE (-2175 2050);
FORCEPROP 1 LAST HDL_TAP TRUE
J 0
(-1850 1875);
DISPLAY 1.446809 (-1850 1875);
PAINT GREEN (-1850 1875);
DISPLAY INVISIBLE (-1850 1875);
FORCEPROP 1 LAST PATH I51
J 0
(-2177 2000);
DISPLAY 0.872340 (-2177 2000);
PAINT GREEN (-2177 2000);
DISPLAY INVISIBLE (-2177 2000);
FORCEADD TAP..1
(-2175 2350);
FORCEPROP 3 LASTPIN (-2225 2350) SIG_NAME P3E_CPU0_PE1_SS_TXP<4>
J 0
(-2215 2360);
DISPLAY 0.659574 (-2215 2360);
PAINT MONO (-2215 2360);
DISPLAY INVISIBLE (-2215 2360);
FORCEPROP 1 LASTPIN (-2225 2350) BN 4
J 0
(-2237 2358);
DISPLAY 0.617021 (-2237 2358);
PAINT PINK (-2237 2358);
FORCEPROP 2 LAST CDS_LIB mstr_standard
J 0
(-2175 2350);
PAINT MONO (-2175 2350);
DISPLAY INVISIBLE (-2175 2350);
FORCEPROP 1 LAST BODY_TYPE PLUMBING
J 0
(-2175 2400);
DISPLAY 1.446809 (-2175 2400);
PAINT GREEN (-2175 2400);
DISPLAY INVISIBLE (-2175 2400);
FORCEPROP 1 LAST HDL_TAP TRUE
J 0
(-1850 2225);
DISPLAY 1.446809 (-1850 2225);
PAINT GREEN (-1850 2225);
DISPLAY INVISIBLE (-1850 2225);
FORCEPROP 1 LAST PATH I52
J 0
(-2177 2350);
DISPLAY 0.872340 (-2177 2350);
PAINT GREEN (-2177 2350);
DISPLAY INVISIBLE (-2177 2350);
FORCEADD TAP..1
(-2175 2400);
FORCEPROP 3 LASTPIN (-2225 2400) SIG_NAME P3E_CPU0_PE1_SS_TXP<5>
J 0
(-2215 2410);
DISPLAY 0.659574 (-2215 2410);
PAINT MONO (-2215 2410);
DISPLAY INVISIBLE (-2215 2410);
FORCEPROP 1 LASTPIN (-2225 2400) BN 5
J 0
(-2237 2408);
DISPLAY 0.617021 (-2237 2408);
PAINT PINK (-2237 2408);
FORCEPROP 2 LAST CDS_LIB mstr_standard
J 0
(-2175 2400);
PAINT MONO (-2175 2400);
DISPLAY INVISIBLE (-2175 2400);
FORCEPROP 1 LAST BODY_TYPE PLUMBING
J 0
(-2175 2450);
DISPLAY 1.446809 (-2175 2450);
PAINT GREEN (-2175 2450);
DISPLAY INVISIBLE (-2175 2450);
FORCEPROP 1 LAST HDL_TAP TRUE
J 0
(-1850 2275);
DISPLAY 1.446809 (-1850 2275);
PAINT GREEN (-1850 2275);
DISPLAY INVISIBLE (-1850 2275);
FORCEPROP 1 LAST PATH I53
J 0
(-2177 2400);
DISPLAY 0.872340 (-2177 2400);
PAINT GREEN (-2177 2400);
DISPLAY INVISIBLE (-2177 2400);
FORCEADD TAP..1
(-2175 2450);
FORCEPROP 3 LASTPIN (-2225 2450) SIG_NAME P3E_CPU0_PE1_SS_TXP<6>
J 0
(-2215 2460);
DISPLAY 0.659574 (-2215 2460);
PAINT MONO (-2215 2460);
DISPLAY INVISIBLE (-2215 2460);
FORCEPROP 1 LASTPIN (-2225 2450) BN 6
J 0
(-2237 2458);
DISPLAY 0.617021 (-2237 2458);
PAINT PINK (-2237 2458);
FORCEPROP 2 LAST CDS_LIB mstr_standard
J 0
(-2175 2450);
PAINT MONO (-2175 2450);
DISPLAY INVISIBLE (-2175 2450);
FORCEPROP 1 LAST BODY_TYPE PLUMBING
J 0
(-2175 2500);
DISPLAY 1.446809 (-2175 2500);
PAINT GREEN (-2175 2500);
DISPLAY INVISIBLE (-2175 2500);
FORCEPROP 1 LAST HDL_TAP TRUE
J 0
(-1850 2325);
DISPLAY 1.446809 (-1850 2325);
PAINT GREEN (-1850 2325);
DISPLAY INVISIBLE (-1850 2325);
FORCEPROP 1 LAST PATH I54
J 0
(-2177 2450);
DISPLAY 0.872340 (-2177 2450);
PAINT GREEN (-2177 2450);
DISPLAY INVISIBLE (-2177 2450);
FORCEADD TAP..1
(-2175 2500);
FORCEPROP 3 LASTPIN (-2225 2500) SIG_NAME P3E_CPU0_PE1_SS_TXP<7>
J 0
(-2215 2510);
DISPLAY 0.659574 (-2215 2510);
PAINT MONO (-2215 2510);
DISPLAY INVISIBLE (-2215 2510);
FORCEPROP 1 LASTPIN (-2225 2500) BN 7
J 0
(-2237 2508);
DISPLAY 0.617021 (-2237 2508);
PAINT PINK (-2237 2508);
FORCEPROP 2 LAST CDS_LIB mstr_standard
J 0
(-2175 2500);
PAINT MONO (-2175 2500);
DISPLAY INVISIBLE (-2175 2500);
FORCEPROP 1 LAST BODY_TYPE PLUMBING
J 0
(-2175 2550);
DISPLAY 1.446809 (-2175 2550);
PAINT GREEN (-2175 2550);
DISPLAY INVISIBLE (-2175 2550);
FORCEPROP 1 LAST HDL_TAP TRUE
J 0
(-1850 2375);
DISPLAY 1.446809 (-1850 2375);
PAINT GREEN (-1850 2375);
DISPLAY INVISIBLE (-1850 2375);
FORCEPROP 1 LAST PATH I55
J 0
(-2177 2500);
DISPLAY 0.872340 (-2177 2500);
PAINT GREEN (-2177 2500);
DISPLAY INVISIBLE (-2177 2500);
FORCEADD TAP..1
(-2175 2850);
FORCEPROP 3 LASTPIN (-2225 2850) SIG_NAME P3E_CPU0_PE1_PCH_TXP<8>
J 0
(-2215 2860);
DISPLAY 0.659574 (-2215 2860);
PAINT MONO (-2215 2860);
DISPLAY INVISIBLE (-2215 2860);
FORCEPROP 1 LASTPIN (-2225 2850) BN 8
J 0
(-2237 2858);
DISPLAY 0.617021 (-2237 2858);
PAINT PINK (-2237 2858);
FORCEPROP 2 LAST CDS_LIB mstr_standard
J 2
(-2175 2850);
PAINT MONO (-2175 2850);
DISPLAY INVISIBLE (-2175 2850);
FORCEPROP 1 LAST BODY_TYPE PLUMBING
J 0
(-2175 2900);
DISPLAY 1.446809 (-2175 2900);
PAINT GREEN (-2175 2900);
DISPLAY INVISIBLE (-2175 2900);
FORCEPROP 1 LAST HDL_TAP TRUE
J 0
(-1850 2725);
DISPLAY 1.446809 (-1850 2725);
PAINT GREEN (-1850 2725);
DISPLAY INVISIBLE (-1850 2725);
FORCEPROP 1 LAST PATH I56
J 0
(-2177 2850);
DISPLAY 0.872340 (-2177 2850);
PAINT GREEN (-2177 2850);
DISPLAY INVISIBLE (-2177 2850);
FORCEADD TAP..1
(-2175 2950);
FORCEPROP 3 LASTPIN (-2225 2950) SIG_NAME P3E_CPU0_PE1_PCH_TXP<10>
J 0
(-2215 2960);
DISPLAY 0.659574 (-2215 2960);
PAINT MONO (-2215 2960);
DISPLAY INVISIBLE (-2215 2960);
FORCEPROP 1 LASTPIN (-2225 2950) BN 10
J 0
(-2237 2958);
DISPLAY 0.617021 (-2237 2958);
PAINT PINK (-2237 2958);
FORCEPROP 2 LAST CDS_LIB mstr_standard
J 2
(-2175 2950);
PAINT MONO (-2175 2950);
DISPLAY INVISIBLE (-2175 2950);
FORCEPROP 1 LAST BODY_TYPE PLUMBING
J 0
(-2175 3000);
DISPLAY 1.446809 (-2175 3000);
PAINT GREEN (-2175 3000);
DISPLAY INVISIBLE (-2175 3000);
FORCEPROP 1 LAST HDL_TAP TRUE
J 0
(-1850 2825);
DISPLAY 1.446809 (-1850 2825);
PAINT GREEN (-1850 2825);
DISPLAY INVISIBLE (-1850 2825);
FORCEPROP 1 LAST PATH I57
J 0
(-2177 2950);
DISPLAY 0.872340 (-2177 2950);
PAINT GREEN (-2177 2950);
DISPLAY INVISIBLE (-2177 2950);
FORCEADD TAP..1
(-2175 2900);
FORCEPROP 3 LASTPIN (-2225 2900) SIG_NAME P3E_CPU0_PE1_PCH_TXP<9>
J 0
(-2215 2910);
DISPLAY 0.659574 (-2215 2910);
PAINT MONO (-2215 2910);
DISPLAY INVISIBLE (-2215 2910);
FORCEPROP 1 LASTPIN (-2225 2900) BN 9
J 0
(-2237 2908);
DISPLAY 0.617021 (-2237 2908);
PAINT PINK (-2237 2908);
FORCEPROP 2 LAST CDS_LIB mstr_standard
J 2
(-2175 2900);
PAINT MONO (-2175 2900);
DISPLAY INVISIBLE (-2175 2900);
FORCEPROP 1 LAST BODY_TYPE PLUMBING
J 0
(-2175 2950);
DISPLAY 1.446809 (-2175 2950);
PAINT GREEN (-2175 2950);
DISPLAY INVISIBLE (-2175 2950);
FORCEPROP 1 LAST HDL_TAP TRUE
J 0
(-1850 2775);
DISPLAY 1.446809 (-1850 2775);
PAINT GREEN (-1850 2775);
DISPLAY INVISIBLE (-1850 2775);
FORCEPROP 1 LAST PATH I58
J 0
(-2177 2900);
DISPLAY 0.872340 (-2177 2900);
PAINT GREEN (-2177 2900);
DISPLAY INVISIBLE (-2177 2900);
FORCEADD TAP..1
(-2625 3100);
FORCEPROP 3 LASTPIN (-2675 3100) SIG_NAME P3E_CPU0_PE1_PCH_TXN<12>
J 0
(-2665 3110);
DISPLAY 0.659574 (-2665 3110);
PAINT MONO (-2665 3110);
DISPLAY INVISIBLE (-2665 3110);
FORCEPROP 1 LASTPIN (-2675 3100) BN 12
J 0
(-2687 3108);
DISPLAY 0.617021 (-2687 3108);
PAINT PINK (-2687 3108);
FORCEPROP 2 LAST CDS_LIB mstr_standard
J 2
(-2625 3100);
PAINT MONO (-2625 3100);
DISPLAY INVISIBLE (-2625 3100);
FORCEPROP 1 LAST BODY_TYPE PLUMBING
J 0
(-2625 3150);
DISPLAY 1.446809 (-2625 3150);
PAINT GREEN (-2625 3150);
DISPLAY INVISIBLE (-2625 3150);
FORCEPROP 1 LAST HDL_TAP TRUE
J 0
(-2300 2975);
DISPLAY 1.446809 (-2300 2975);
PAINT GREEN (-2300 2975);
DISPLAY INVISIBLE (-2300 2975);
FORCEPROP 1 LAST PATH I59
J 0
(-2627 3100);
DISPLAY 0.872340 (-2627 3100);
PAINT GREEN (-2627 3100);
DISPLAY INVISIBLE (-2627 3100);
FORCEADD TAP..1
R 2
(-5825 2000);
FORCEPROP 3 LASTPIN (-5775 2000) SIG_NAME P3E_CPU0_PE1_SS_RXP<3>
J 0
(-5765 2010);
DISPLAY 0.659574 (-5765 2010);
PAINT MONO (-5765 2010);
DISPLAY INVISIBLE (-5765 2010);
FORCEPROP 1 LASTPIN (-5775 2000) BN 3
J 2
(-5763 2008);
DISPLAY 0.617021 (-5763 2008);
PAINT PINK (-5763 2008);
FORCEPROP 2 LAST CDS_LIB mstr_standard
J 0
(-5825 2000);
PAINT MONO (-5825 2000);
DISPLAY INVISIBLE (-5825 2000);
FORCEPROP 1 LAST BODY_TYPE PLUMBING
J 2
(-5825 2050);
DISPLAY 1.446809 (-5825 2050);
PAINT GREEN (-5825 2050);
DISPLAY INVISIBLE (-5825 2050);
FORCEPROP 1 LAST HDL_TAP TRUE
J 2
(-6150 1875);
DISPLAY 1.446809 (-6150 1875);
PAINT GREEN (-6150 1875);
DISPLAY INVISIBLE (-6150 1875);
FORCEPROP 1 LAST PATH I6
J 2
(-5823 2000);
DISPLAY 0.872340 (-5823 2000);
PAINT GREEN (-5823 2000);
DISPLAY INVISIBLE (-5823 2000);
FORCEADD TAP..1
(-2625 3150);
FORCEPROP 3 LASTPIN (-2675 3150) SIG_NAME P3E_CPU0_PE1_PCH_TXN<13>
J 0
(-2665 3160);
DISPLAY 0.659574 (-2665 3160);
PAINT MONO (-2665 3160);
DISPLAY INVISIBLE (-2665 3160);
FORCEPROP 1 LASTPIN (-2675 3150) BN 13
J 0
(-2687 3158);
DISPLAY 0.617021 (-2687 3158);
PAINT PINK (-2687 3158);
FORCEPROP 2 LAST CDS_LIB mstr_standard
J 2
(-2625 3150);
PAINT MONO (-2625 3150);
DISPLAY INVISIBLE (-2625 3150);
FORCEPROP 1 LAST BODY_TYPE PLUMBING
J 0
(-2625 3200);
DISPLAY 1.446809 (-2625 3200);
PAINT GREEN (-2625 3200);
DISPLAY INVISIBLE (-2625 3200);
FORCEPROP 1 LAST HDL_TAP TRUE
J 0
(-2300 3025);
DISPLAY 1.446809 (-2300 3025);
PAINT GREEN (-2300 3025);
DISPLAY INVISIBLE (-2300 3025);
FORCEPROP 1 LAST PATH I60
J 0
(-2627 3150);
DISPLAY 0.872340 (-2627 3150);
PAINT GREEN (-2627 3150);
DISPLAY INVISIBLE (-2627 3150);
FORCEADD TAP..1
(-2625 3250);
FORCEPROP 3 LASTPIN (-2675 3250) SIG_NAME P3E_CPU0_PE1_PCH_TXN<15>
J 0
(-2665 3260);
DISPLAY 0.659574 (-2665 3260);
PAINT MONO (-2665 3260);
DISPLAY INVISIBLE (-2665 3260);
FORCEPROP 1 LASTPIN (-2675 3250) BN 15
J 0
(-2687 3258);
DISPLAY 0.617021 (-2687 3258);
PAINT PINK (-2687 3258);
FORCEPROP 2 LAST CDS_LIB mstr_standard
J 2
(-2625 3250);
PAINT MONO (-2625 3250);
DISPLAY INVISIBLE (-2625 3250);
FORCEPROP 1 LAST BODY_TYPE PLUMBING
J 0
(-2625 3300);
DISPLAY 1.446809 (-2625 3300);
PAINT GREEN (-2625 3300);
DISPLAY INVISIBLE (-2625 3300);
FORCEPROP 1 LAST HDL_TAP TRUE
J 0
(-2300 3125);
DISPLAY 1.446809 (-2300 3125);
PAINT GREEN (-2300 3125);
DISPLAY INVISIBLE (-2300 3125);
FORCEPROP 1 LAST PATH I61
J 0
(-2627 3250);
DISPLAY 0.872340 (-2627 3250);
PAINT GREEN (-2627 3250);
DISPLAY INVISIBLE (-2627 3250);
FORCEADD TAP..1
(-2625 3200);
FORCEPROP 3 LASTPIN (-2675 3200) SIG_NAME P3E_CPU0_PE1_PCH_TXN<14>
J 0
(-2665 3210);
DISPLAY 0.659574 (-2665 3210);
PAINT MONO (-2665 3210);
DISPLAY INVISIBLE (-2665 3210);
FORCEPROP 1 LASTPIN (-2675 3200) BN 14
J 0
(-2687 3208);
DISPLAY 0.617021 (-2687 3208);
PAINT PINK (-2687 3208);
FORCEPROP 2 LAST CDS_LIB mstr_standard
J 2
(-2625 3200);
PAINT MONO (-2625 3200);
DISPLAY INVISIBLE (-2625 3200);
FORCEPROP 1 LAST BODY_TYPE PLUMBING
J 0
(-2625 3250);
DISPLAY 1.446809 (-2625 3250);
PAINT GREEN (-2625 3250);
DISPLAY INVISIBLE (-2625 3250);
FORCEPROP 1 LAST HDL_TAP TRUE
J 0
(-2300 3075);
DISPLAY 1.446809 (-2300 3075);
PAINT GREEN (-2300 3075);
DISPLAY INVISIBLE (-2300 3075);
FORCEPROP 1 LAST PATH I62
J 0
(-2627 3200);
DISPLAY 0.872340 (-2627 3200);
PAINT GREEN (-2627 3200);
DISPLAY INVISIBLE (-2627 3200);
FORCEADD TAP..1
(-2175 3350);
FORCEPROP 3 LASTPIN (-2225 3350) SIG_NAME P3E_CPU0_PE1_PCH_TXP<12>
J 0
(-2215 3360);
DISPLAY 0.659574 (-2215 3360);
PAINT MONO (-2215 3360);
DISPLAY INVISIBLE (-2215 3360);
FORCEPROP 1 LASTPIN (-2225 3350) BN 12
J 0
(-2237 3358);
DISPLAY 0.617021 (-2237 3358);
PAINT PINK (-2237 3358);
FORCEPROP 2 LAST CDS_LIB mstr_standard
J 2
(-2175 3350);
PAINT MONO (-2175 3350);
DISPLAY INVISIBLE (-2175 3350);
FORCEPROP 1 LAST BODY_TYPE PLUMBING
J 0
(-2175 3400);
DISPLAY 1.446809 (-2175 3400);
PAINT GREEN (-2175 3400);
DISPLAY INVISIBLE (-2175 3400);
FORCEPROP 1 LAST HDL_TAP TRUE
J 0
(-1850 3225);
DISPLAY 1.446809 (-1850 3225);
PAINT GREEN (-1850 3225);
DISPLAY INVISIBLE (-1850 3225);
FORCEPROP 1 LAST PATH I64
J 0
(-2177 3350);
DISPLAY 0.872340 (-2177 3350);
PAINT GREEN (-2177 3350);
DISPLAY INVISIBLE (-2177 3350);
FORCEADD TAP..1
(-2175 3400);
FORCEPROP 3 LASTPIN (-2225 3400) SIG_NAME P3E_CPU0_PE1_PCH_TXP<13>
J 0
(-2215 3410);
DISPLAY 0.659574 (-2215 3410);
PAINT MONO (-2215 3410);
DISPLAY INVISIBLE (-2215 3410);
FORCEPROP 1 LASTPIN (-2225 3400) BN 13
J 0
(-2237 3408);
DISPLAY 0.617021 (-2237 3408);
PAINT PINK (-2237 3408);
FORCEPROP 2 LAST CDS_LIB mstr_standard
J 2
(-2175 3400);
PAINT MONO (-2175 3400);
DISPLAY INVISIBLE (-2175 3400);
FORCEPROP 1 LAST BODY_TYPE PLUMBING
J 0
(-2175 3450);
DISPLAY 1.446809 (-2175 3450);
PAINT GREEN (-2175 3450);
DISPLAY INVISIBLE (-2175 3450);
FORCEPROP 1 LAST HDL_TAP TRUE
J 0
(-1850 3275);
DISPLAY 1.446809 (-1850 3275);
PAINT GREEN (-1850 3275);
DISPLAY INVISIBLE (-1850 3275);
FORCEPROP 1 LAST PATH I65
J 0
(-2177 3400);
DISPLAY 0.872340 (-2177 3400);
PAINT GREEN (-2177 3400);
DISPLAY INVISIBLE (-2177 3400);
FORCEADD TAP..1
(-2175 3500);
FORCEPROP 3 LASTPIN (-2225 3500) SIG_NAME P3E_CPU0_PE1_PCH_TXP<15>
J 0
(-2215 3510);
DISPLAY 0.659574 (-2215 3510);
PAINT MONO (-2215 3510);
DISPLAY INVISIBLE (-2215 3510);
FORCEPROP 1 LASTPIN (-2225 3500) BN 15
J 0
(-2237 3508);
DISPLAY 0.617021 (-2237 3508);
PAINT PINK (-2237 3508);
FORCEPROP 2 LAST CDS_LIB mstr_standard
J 2
(-2175 3500);
PAINT MONO (-2175 3500);
DISPLAY INVISIBLE (-2175 3500);
FORCEPROP 1 LAST BODY_TYPE PLUMBING
J 0
(-2175 3550);
DISPLAY 1.446809 (-2175 3550);
PAINT GREEN (-2175 3550);
DISPLAY INVISIBLE (-2175 3550);
FORCEPROP 1 LAST HDL_TAP TRUE
J 0
(-1850 3375);
DISPLAY 1.446809 (-1850 3375);
PAINT GREEN (-1850 3375);
DISPLAY INVISIBLE (-1850 3375);
FORCEPROP 1 LAST PATH I66
J 0
(-2177 3500);
DISPLAY 0.872340 (-2177 3500);
PAINT GREEN (-2177 3500);
DISPLAY INVISIBLE (-2177 3500);
FORCEADD TAP..1
(-2175 3450);
FORCEPROP 3 LASTPIN (-2225 3450) SIG_NAME P3E_CPU0_PE1_PCH_TXP<14>
J 0
(-2215 3460);
DISPLAY 0.659574 (-2215 3460);
PAINT MONO (-2215 3460);
DISPLAY INVISIBLE (-2215 3460);
FORCEPROP 1 LASTPIN (-2225 3450) BN 14
J 0
(-2237 3458);
DISPLAY 0.617021 (-2237 3458);
PAINT PINK (-2237 3458);
FORCEPROP 2 LAST CDS_LIB mstr_standard
J 2
(-2175 3450);
PAINT MONO (-2175 3450);
DISPLAY INVISIBLE (-2175 3450);
FORCEPROP 1 LAST BODY_TYPE PLUMBING
J 0
(-2175 3500);
DISPLAY 1.446809 (-2175 3500);
PAINT GREEN (-2175 3500);
DISPLAY INVISIBLE (-2175 3500);
FORCEPROP 1 LAST HDL_TAP TRUE
J 0
(-1850 3325);
DISPLAY 1.446809 (-1850 3325);
PAINT GREEN (-1850 3325);
DISPLAY INVISIBLE (-1850 3325);
FORCEPROP 1 LAST PATH I67
J 0
(-2177 3450);
DISPLAY 0.872340 (-2177 3450);
PAINT GREEN (-2177 3450);
DISPLAY INVISIBLE (-2177 3450);
FORCEADD TAP..1
R 2
(-5825 2350);
FORCEPROP 3 LASTPIN (-5775 2350) SIG_NAME P3E_CPU0_PE1_SS_RXP<4>
J 0
(-5765 2360);
DISPLAY 0.659574 (-5765 2360);
PAINT MONO (-5765 2360);
DISPLAY INVISIBLE (-5765 2360);
FORCEPROP 1 LASTPIN (-5775 2350) BN 4
J 2
(-5763 2358);
DISPLAY 0.617021 (-5763 2358);
PAINT PINK (-5763 2358);
FORCEPROP 2 LAST CDS_LIB mstr_standard
J 0
(-5825 2350);
PAINT MONO (-5825 2350);
DISPLAY INVISIBLE (-5825 2350);
FORCEPROP 1 LAST BODY_TYPE PLUMBING
J 2
(-5825 2400);
DISPLAY 1.446809 (-5825 2400);
PAINT GREEN (-5825 2400);
DISPLAY INVISIBLE (-5825 2400);
FORCEPROP 1 LAST HDL_TAP TRUE
J 2
(-6150 2225);
DISPLAY 1.446809 (-6150 2225);
PAINT GREEN (-6150 2225);
DISPLAY INVISIBLE (-6150 2225);
FORCEPROP 1 LAST PATH I7
J 2
(-5823 2350);
DISPLAY 0.872340 (-5823 2350);
PAINT GREEN (-5823 2350);
DISPLAY INVISIBLE (-5823 2350);
FORCEADD OFFPAGE..1
(-6775 3650);
FORCEPROP 2 LAST $XR0 105 
J 0
(-7027 3650);
DISPLAY 0.638298 (-7027 3650);
PAINT MONO (-7027 3650);
FORCEPROP 2 LAST $XR1 244 
J 0
(-7027 3650);
DISPLAY 0.638298 (-7027 3650);
PAINT MONO (-7027 3650);
FORCEPROP 2 LAST CDS_LIB mstr_standard
J 0
(-6775 3650);
PAINT MONO (-6775 3650);
DISPLAY INVISIBLE (-6775 3650);
FORCEPROP 1 LAST OFFPAGE TRUE
J 0
(-6450 3525);
PAINT GREEN (-6450 3525);
DISPLAY INVISIBLE (-6450 3525);
FORCEPROP 1 LAST COMMENT_BODY TRUE
J 0
(-6650 3550);
DISPLAY 1.170213 (-6650 3550);
PAINT GREEN (-6650 3550);
DISPLAY INVISIBLE (-6650 3550);
FORCEPROP 2 LAST PATH I70
J 0
(-7025 3700);
DISPLAY 1.021277 (-7025 3700);
PAINT ORANGE (-7025 3700);
DISPLAY INVISIBLE (-7025 3700);
FORCEADD OFFPAGE..1
(-6775 3525);
FORCEPROP 2 LAST $XR0 105 
J 0
(-7027 3525);
DISPLAY 0.638298 (-7027 3525);
PAINT MONO (-7027 3525);
FORCEPROP 2 LAST $XR1 244 
J 0
(-7027 3525);
DISPLAY 0.638298 (-7027 3525);
PAINT MONO (-7027 3525);
FORCEPROP 2 LAST CDS_LIB mstr_standard
J 0
(-6775 3525);
PAINT MONO (-6775 3525);
DISPLAY INVISIBLE (-6775 3525);
FORCEPROP 1 LAST OFFPAGE TRUE
J 0
(-6450 3400);
PAINT GREEN (-6450 3400);
DISPLAY INVISIBLE (-6450 3400);
FORCEPROP 1 LAST COMMENT_BODY TRUE
J 0
(-6650 3425);
DISPLAY 1.170213 (-6650 3425);
PAINT GREEN (-6650 3425);
DISPLAY INVISIBLE (-6650 3425);
FORCEPROP 2 LAST PATH I71
J 0
(-7025 3575);
DISPLAY 1.021277 (-7025 3575);
PAINT ORANGE (-7025 3575);
DISPLAY INVISIBLE (-7025 3575);
FORCEADD OFFPAGE..2
(-1150 3575);
FORCEPROP 2 LAST $XR0 105 
J 0
(-961 3575);
DISPLAY 0.638298 (-961 3575);
PAINT MONO (-961 3575);
FORCEPROP 2 LAST $XR1 244 
J 0
(-961 3575);
DISPLAY 0.638298 (-961 3575);
PAINT MONO (-961 3575);
FORCEPROP 2 LAST CDS_LIB mstr_standard
J 0
(-1150 3575);
PAINT ORANGE (-1150 3575);
DISPLAY INVISIBLE (-1150 3575);
FORCEPROP 1 LAST OFFPAGE TRUE
J 0
(-825 3450);
PAINT GREEN (-825 3450);
DISPLAY INVISIBLE (-825 3450);
FORCEPROP 1 LAST COMMENT_BODY TRUE
J 0
(-1195 3480);
DISPLAY 1.170213 (-1195 3480);
PAINT GREEN (-1195 3480);
DISPLAY INVISIBLE (-1195 3480);
FORCEPROP 2 LAST PATH I74
J 0
(-975 3650);
DISPLAY 1.021277 (-975 3650);
PAINT ORANGE (-975 3650);
DISPLAY INVISIBLE (-975 3650);
FORCEADD OFFPAGE..2
(-1150 3725);
FORCEPROP 2 LAST $XR0 105 
J 0
(-961 3725);
DISPLAY 0.638298 (-961 3725);
PAINT MONO (-961 3725);
FORCEPROP 2 LAST $XR1 244 
J 0
(-961 3725);
DISPLAY 0.638298 (-961 3725);
PAINT MONO (-961 3725);
FORCEPROP 2 LAST CDS_LIB mstr_standard
J 0
(-1150 3725);
PAINT ORANGE (-1150 3725);
DISPLAY INVISIBLE (-1150 3725);
FORCEPROP 1 LAST OFFPAGE TRUE
J 0
(-825 3600);
PAINT GREEN (-825 3600);
DISPLAY INVISIBLE (-825 3600);
FORCEPROP 1 LAST COMMENT_BODY TRUE
J 0
(-1195 3630);
DISPLAY 1.170213 (-1195 3630);
PAINT GREEN (-1195 3630);
DISPLAY INVISIBLE (-1195 3630);
FORCEPROP 2 LAST PATH I75
J 0
(-975 3800);
DISPLAY 1.021277 (-975 3800);
PAINT ORANGE (-975 3800);
DISPLAY INVISIBLE (-975 3800);
FORCEADD TAP..1
(-2175 3000);
FORCEPROP 3 LASTPIN (-2225 3000) SIG_NAME P3E_CPU0_PE1_PCH_TXP<11>
J 0
(-2215 3010);
DISPLAY 0.659574 (-2215 3010);
PAINT MONO (-2215 3010);
DISPLAY INVISIBLE (-2215 3010);
FORCEPROP 1 LASTPIN (-2225 3000) BN 11
J 0
(-2237 3008);
DISPLAY 0.617021 (-2237 3008);
PAINT GREEN (-2237 3008);
FORCEPROP 2 LAST CDS_LIB mstr_standard
J 0
(-2175 3000);
PAINT ORANGE (-2175 3000);
DISPLAY INVISIBLE (-2175 3000);
FORCEPROP 1 LAST BODY_TYPE PLUMBING
J 0
(-2175 3050);
DISPLAY 1.446809 (-2175 3050);
PAINT GREEN (-2175 3050);
DISPLAY INVISIBLE (-2175 3050);
FORCEPROP 1 LAST HDL_TAP TRUE
J 0
(-1850 2875);
DISPLAY 1.446809 (-1850 2875);
PAINT GREEN (-1850 2875);
DISPLAY INVISIBLE (-1850 2875);
FORCEPROP 1 LAST PATH I78
J 0
(-2177 3000);
DISPLAY 0.872340 (-2177 3000);
PAINT GREEN (-2177 3000);
DISPLAY INVISIBLE (-2177 3000);
FORCEADD TAP..1
(-2625 2750);
FORCEPROP 3 LASTPIN (-2675 2750) SIG_NAME P3E_CPU0_PE1_PCH_TXN<11>
J 0
(-2665 2760);
DISPLAY 0.659574 (-2665 2760);
PAINT MONO (-2665 2760);
DISPLAY INVISIBLE (-2665 2760);
FORCEPROP 1 LASTPIN (-2675 2750) BN 11
J 0
(-2687 2758);
DISPLAY 0.617021 (-2687 2758);
PAINT PINK (-2687 2758);
FORCEPROP 2 LAST CDS_LIB mstr_standard
J 2
(-2625 2750);
PAINT MONO (-2625 2750);
DISPLAY INVISIBLE (-2625 2750);
FORCEPROP 1 LAST BODY_TYPE PLUMBING
J 0
(-2625 2800);
DISPLAY 1.446809 (-2625 2800);
PAINT GREEN (-2625 2800);
DISPLAY INVISIBLE (-2625 2800);
FORCEPROP 1 LAST HDL_TAP TRUE
J 0
(-2300 2625);
DISPLAY 1.446809 (-2300 2625);
PAINT GREEN (-2300 2625);
DISPLAY INVISIBLE (-2300 2625);
FORCEPROP 1 LAST PATH I79
J 0
(-2627 2750);
DISPLAY 0.872340 (-2627 2750);
PAINT GREEN (-2627 2750);
DISPLAY INVISIBLE (-2627 2750);
FORCEADD TAP..1
R 2
(-5825 2400);
FORCEPROP 3 LASTPIN (-5775 2400) SIG_NAME P3E_CPU0_PE1_SS_RXP<5>
J 0
(-5765 2410);
DISPLAY 0.659574 (-5765 2410);
PAINT MONO (-5765 2410);
DISPLAY INVISIBLE (-5765 2410);
FORCEPROP 1 LASTPIN (-5775 2400) BN 5
J 2
(-5763 2408);
DISPLAY 0.617021 (-5763 2408);
PAINT PINK (-5763 2408);
FORCEPROP 2 LAST CDS_LIB mstr_standard
J 0
(-5825 2400);
PAINT MONO (-5825 2400);
DISPLAY INVISIBLE (-5825 2400);
FORCEPROP 1 LAST BODY_TYPE PLUMBING
J 2
(-5825 2450);
DISPLAY 1.446809 (-5825 2450);
PAINT GREEN (-5825 2450);
DISPLAY INVISIBLE (-5825 2450);
FORCEPROP 1 LAST HDL_TAP TRUE
J 2
(-6150 2275);
DISPLAY 1.446809 (-6150 2275);
PAINT GREEN (-6150 2275);
DISPLAY INVISIBLE (-6150 2275);
FORCEPROP 1 LAST PATH I8
J 2
(-5823 2400);
DISPLAY 0.872340 (-5823 2400);
PAINT GREEN (-5823 2400);
DISPLAY INVISIBLE (-5823 2400);
FORCEADD OFFPAGE..2
(-1075 1550);
FORCEPROP 2 LAST $XR0 107 
J 0
(-886 1550);
DISPLAY 0.638298 (-886 1550);
PAINT MONO (-886 1550);
FORCEPROP 2 LAST CDS_LIB mstr_standard
J 0
(-1075 1550);
PAINT ORANGE (-1075 1550);
DISPLAY INVISIBLE (-1075 1550);
FORCEPROP 1 LAST OFFPAGE TRUE
J 0
(-750 1425);
PAINT GREEN (-750 1425);
DISPLAY INVISIBLE (-750 1425);
FORCEPROP 1 LAST COMMENT_BODY TRUE
J 0
(-1120 1455);
DISPLAY 1.170213 (-1120 1455);
PAINT GREEN (-1120 1455);
DISPLAY INVISIBLE (-1120 1455);
FORCEPROP 2 LAST PATH I80
J 0
(-900 1625);
DISPLAY 1.021277 (-900 1625);
PAINT ORANGE (-900 1625);
DISPLAY INVISIBLE (-900 1625);
FORCEADD OFFPAGE..2
(-1100 1775);
FORCEPROP 2 LAST $XR0 107 
J 0
(-911 1775);
DISPLAY 0.638298 (-911 1775);
PAINT MONO (-911 1775);
FORCEPROP 2 LAST CDS_LIB mstr_standard
J 0
(-1100 1775);
PAINT ORANGE (-1100 1775);
DISPLAY INVISIBLE (-1100 1775);
FORCEPROP 1 LAST OFFPAGE TRUE
J 0
(-775 1650);
PAINT GREEN (-775 1650);
DISPLAY INVISIBLE (-775 1650);
FORCEPROP 1 LAST COMMENT_BODY TRUE
J 0
(-1145 1680);
DISPLAY 1.170213 (-1145 1680);
PAINT GREEN (-1145 1680);
DISPLAY INVISIBLE (-1145 1680);
FORCEPROP 2 LAST PATH I81
J 0
(-925 1850);
DISPLAY 1.021277 (-925 1850);
PAINT ORANGE (-925 1850);
DISPLAY INVISIBLE (-925 1850);
FORCEADD OFFPAGE..1
(-6975 1800);
FORCEPROP 2 LAST $XR0 107 
J 0
(-7227 1800);
DISPLAY 0.638298 (-7227 1800);
PAINT MONO (-7227 1800);
FORCEPROP 2 LAST CDS_LIB mstr_standard
J 0
(-6975 1800);
PAINT ORANGE (-6975 1800);
DISPLAY INVISIBLE (-6975 1800);
FORCEPROP 1 LAST OFFPAGE TRUE
J 0
(-6650 1675);
PAINT GREEN (-6650 1675);
DISPLAY INVISIBLE (-6650 1675);
FORCEPROP 1 LAST COMMENT_BODY TRUE
J 0
(-6850 1700);
DISPLAY 1.170213 (-6850 1700);
PAINT GREEN (-6850 1700);
DISPLAY INVISIBLE (-6850 1700);
FORCEPROP 2 LAST PATH I82
J 0
(-6925 1875);
DISPLAY 1.021277 (-6925 1875);
PAINT ORANGE (-6925 1875);
DISPLAY INVISIBLE (-6925 1875);
FORCEADD OFFPAGE..1
(-6975 1525);
FORCEPROP 2 LAST $XR0 107 
J 0
(-7227 1525);
DISPLAY 0.638298 (-7227 1525);
PAINT MONO (-7227 1525);
FORCEPROP 2 LAST CDS_LIB mstr_standard
J 0
(-6975 1525);
PAINT ORANGE (-6975 1525);
DISPLAY INVISIBLE (-6975 1525);
FORCEPROP 1 LAST OFFPAGE TRUE
J 0
(-6650 1400);
PAINT GREEN (-6650 1400);
DISPLAY INVISIBLE (-6650 1400);
FORCEPROP 1 LAST COMMENT_BODY TRUE
J 0
(-6850 1425);
DISPLAY 1.170213 (-6850 1425);
PAINT GREEN (-6850 1425);
DISPLAY INVISIBLE (-6850 1425);
FORCEPROP 2 LAST PATH I83
J 0
(-6925 1600);
DISPLAY 1.021277 (-6925 1600);
PAINT ORANGE (-6925 1600);
DISPLAY INVISIBLE (-6925 1600);
FORCEADD SKX_EXT_B..10
(-4100 2550);
FORCEPROP 1 LAST LOCATION U5D1
J 0
(-4800 3750);
DISPLAY 0.617021 (-4800 3750);
PAINT AQUA (-4800 3750);
FORCEPROP 1 LAST PART_NUMBER TBD
J 0
(-4800 1400);
DISPLAY 0.617021 (-4800 1400);
PAINT BLUE (-4800 1400);
FORCEPROP 1 LAST MATERIAL IC
J 0
(-4800 3700);
DISPLAY 0.617021 (-4800 3700);
PAINT SKYBLUE (-4800 3700);
FORCEPROP 2 LASTPIN (-3350 3500) $PN EC8
J 0
(-3340 3510);
DISPLAY 0.617021 (-3340 3510);
PAINT ORANGE (-3340 3510);
FORCEPROP 2 LASTPIN (-3350 3450) $PN EB7
J 0
(-3340 3460);
DISPLAY 0.617021 (-3340 3460);
PAINT ORANGE (-3340 3460);
FORCEPROP 2 LASTPIN (-3350 3400) $PN DW6
J 0
(-3340 3410);
DISPLAY 0.617021 (-3340 3410);
PAINT ORANGE (-3340 3410);
FORCEPROP 2 LASTPIN (-3350 3350) $PN DT7
J 0
(-3340 3360);
DISPLAY 0.617021 (-3340 3360);
PAINT ORANGE (-3340 3360);
FORCEPROP 2 LASTPIN (-3350 3000) $PN DV5
J 0
(-3340 3010);
DISPLAY 0.617021 (-3340 3010);
PAINT ORANGE (-3340 3010);
FORCEPROP 2 LASTPIN (-3350 2950) $PN DU4
J 0
(-3340 2960);
DISPLAY 0.617021 (-3340 2960);
PAINT ORANGE (-3340 2960);
FORCEPROP 2 LASTPIN (-3350 2900) $PN DU2
J 0
(-3340 2910);
DISPLAY 0.617021 (-3340 2910);
PAINT ORANGE (-3340 2910);
FORCEPROP 2 LASTPIN (-3350 2850) $PN DR4
J 0
(-3340 2860);
DISPLAY 0.617021 (-3340 2860);
PAINT ORANGE (-3340 2860);
FORCEPROP 2 LASTPIN (-3350 2500) $PN DP3
J 0
(-3340 2510);
DISPLAY 0.617021 (-3340 2510);
PAINT ORANGE (-3340 2510);
FORCEPROP 2 LASTPIN (-3350 2450) $PN DL2
J 0
(-3340 2460);
DISPLAY 0.617021 (-3340 2460);
PAINT ORANGE (-3340 2460);
FORCEPROP 2 LASTPIN (-3350 2400) $PN DH3
J 0
(-3340 2410);
DISPLAY 0.617021 (-3340 2410);
PAINT ORANGE (-3340 2410);
FORCEPROP 2 LASTPIN (-3350 2350) $PN DF3
J 0
(-3340 2360);
DISPLAY 0.617021 (-3340 2360);
PAINT ORANGE (-3340 2360);
FORCEPROP 2 LASTPIN (-3350 2000) $PN DC4
J 0
(-3340 2010);
DISPLAY 0.617021 (-3340 2010);
PAINT ORANGE (-3340 2010);
FORCEPROP 2 LASTPIN (-3350 1950) $PN DD3
J 0
(-3340 1960);
DISPLAY 0.617021 (-3340 1960);
PAINT ORANGE (-3340 1960);
FORCEPROP 2 LASTPIN (-3350 1900) $PN DB1
J 0
(-3340 1910);
DISPLAY 0.617021 (-3340 1910);
PAINT ORANGE (-3340 1910);
FORCEPROP 2 LASTPIN (-3350 1850) $PN CW2
J 0
(-3340 1860);
DISPLAY 0.617021 (-3340 1860);
PAINT ORANGE (-3340 1860);
FORCEPROP 2 LASTPIN (-3350 3250) $PN ED9
J 0
(-3340 3260);
DISPLAY 0.617021 (-3340 3260);
PAINT ORANGE (-3340 3260);
FORCEPROP 2 LASTPIN (-3350 3200) $PN EA8
J 0
(-3340 3210);
DISPLAY 0.617021 (-3340 3210);
PAINT ORANGE (-3340 3210);
FORCEPROP 2 LASTPIN (-3350 3150) $PN DY7
J 0
(-3340 3160);
DISPLAY 0.617021 (-3340 3160);
PAINT ORANGE (-3340 3160);
FORCEPROP 2 LASTPIN (-3350 3100) $PN DV7
J 0
(-3340 3110);
DISPLAY 0.617021 (-3340 3110);
PAINT ORANGE (-3340 3110);
FORCEPROP 2 LASTPIN (-3350 2750) $PN DU6
J 0
(-3340 2760);
DISPLAY 0.617021 (-3340 2760);
PAINT ORANGE (-3340 2760);
FORCEPROP 2 LASTPIN (-3350 2700) $PN DW4
J 0
(-3340 2710);
DISPLAY 0.617021 (-3340 2710);
PAINT ORANGE (-3340 2710);
FORCEPROP 2 LASTPIN (-3350 2650) $PN DV3
J 0
(-3340 2660);
DISPLAY 0.617021 (-3340 2660);
PAINT ORANGE (-3340 2660);
FORCEPROP 2 LASTPIN (-3350 2600) $PN DT5
J 0
(-3340 2610);
DISPLAY 0.617021 (-3340 2610);
PAINT ORANGE (-3340 2610);
FORCEPROP 2 LASTPIN (-3350 2250) $PN DN4
J 0
(-3340 2260);
DISPLAY 0.617021 (-3340 2260);
PAINT ORANGE (-3340 2260);
FORCEPROP 2 LASTPIN (-3350 2200) $PN DM3
J 0
(-3340 2210);
DISPLAY 0.617021 (-3340 2210);
PAINT ORANGE (-3340 2210);
FORCEPROP 2 LASTPIN (-3350 2150) $PN DK3
J 0
(-3340 2160);
DISPLAY 0.617021 (-3340 2160);
PAINT ORANGE (-3340 2160);
FORCEPROP 2 LASTPIN (-3350 2100) $PN DG4
J 0
(-3340 2110);
DISPLAY 0.617021 (-3340 2110);
PAINT ORANGE (-3340 2110);
FORCEPROP 2 LASTPIN (-3350 1750) $PN DE4
J 0
(-3340 1760);
DISPLAY 0.617021 (-3340 1760);
PAINT ORANGE (-3340 1760);
FORCEPROP 2 LASTPIN (-3350 1700) $PN DE2
J 0
(-3340 1710);
DISPLAY 0.617021 (-3340 1710);
PAINT ORANGE (-3340 1710);
FORCEPROP 2 LASTPIN (-3350 1650) $PN DC2
J 0
(-3340 1660);
DISPLAY 0.617021 (-3340 1660);
PAINT ORANGE (-3340 1660);
FORCEPROP 2 LASTPIN (-3350 1600) $PN DA2
J 0
(-3340 1610);
DISPLAY 0.617021 (-3340 1610);
PAINT ORANGE (-3340 1610);
FORCEPROP 2 LASTPIN (-4850 3500) $PN DT15
J 2
(-4860 3510);
DISPLAY 0.617021 (-4860 3510);
PAINT ORANGE (-4860 3510);
FORCEPROP 2 LASTPIN (-4850 3450) $PN DV15
J 2
(-4860 3460);
DISPLAY 0.617021 (-4860 3460);
PAINT ORANGE (-4860 3460);
FORCEPROP 2 LASTPIN (-4850 3400) $PN DY13
J 2
(-4860 3410);
DISPLAY 0.617021 (-4860 3410);
PAINT ORANGE (-4860 3410);
FORCEPROP 2 LASTPIN (-4850 3350) $PN DU12
J 2
(-4860 3360);
DISPLAY 0.617021 (-4860 3360);
PAINT ORANGE (-4860 3360);
FORCEPROP 2 LASTPIN (-4850 3000) $PN DP13
J 2
(-4860 3010);
DISPLAY 0.617021 (-4860 3010);
PAINT ORANGE (-4860 3010);
FORCEPROP 2 LASTPIN (-4850 2950) $PN DR12
J 2
(-4860 2960);
DISPLAY 0.617021 (-4860 2960);
PAINT ORANGE (-4860 2960);
FORCEPROP 2 LASTPIN (-4850 2900) $PN DN10
J 2
(-4860 2910);
DISPLAY 0.617021 (-4860 2910);
PAINT ORANGE (-4860 2910);
FORCEPROP 2 LASTPIN (-4850 2850) $PN DK11
J 2
(-4860 2860);
DISPLAY 0.617021 (-4860 2860);
PAINT ORANGE (-4860 2860);
FORCEPROP 2 LASTPIN (-4850 2500) $PN DL10
J 2
(-4860 2510);
DISPLAY 0.617021 (-4860 2510);
PAINT ORANGE (-4860 2510);
FORCEPROP 2 LASTPIN (-4850 2450) $PN DJ8
J 2
(-4860 2460);
DISPLAY 0.617021 (-4860 2460);
PAINT ORANGE (-4860 2460);
FORCEPROP 2 LASTPIN (-4850 2400) $PN DF9
J 2
(-4860 2410);
DISPLAY 0.617021 (-4860 2410);
PAINT ORANGE (-4860 2410);
FORCEPROP 2 LASTPIN (-4850 2350) $PN DD9
J 2
(-4860 2360);
DISPLAY 0.617021 (-4860 2360);
PAINT ORANGE (-4860 2360);
FORCEPROP 2 LASTPIN (-4850 2000) $PN DA10
J 2
(-4860 2010);
DISPLAY 0.617021 (-4860 2010);
PAINT ORANGE (-4860 2010);
FORCEPROP 2 LASTPIN (-4850 1950) $PN DB9
J 2
(-4860 1960);
DISPLAY 0.617021 (-4860 1960);
PAINT ORANGE (-4860 1960);
FORCEPROP 2 LASTPIN (-4850 1900) $PN CY7
J 2
(-4860 1910);
DISPLAY 0.617021 (-4860 1910);
PAINT ORANGE (-4860 1910);
FORCEPROP 2 LASTPIN (-4850 1850) $PN CU8
J 2
(-4860 1860);
DISPLAY 0.617021 (-4860 1860);
PAINT ORANGE (-4860 1860);
FORCEPROP 2 LASTPIN (-4850 3250) $PN DU16
J 2
(-4860 3260);
DISPLAY 0.617021 (-4860 3260);
PAINT ORANGE (-4860 3260);
FORCEPROP 2 LASTPIN (-4850 3200) $PN DY15
J 2
(-4860 3210);
DISPLAY 0.617021 (-4860 3210);
PAINT ORANGE (-4860 3210);
FORCEPROP 2 LASTPIN (-4850 3150) $PN DW14
J 2
(-4860 3160);
DISPLAY 0.617021 (-4860 3160);
PAINT ORANGE (-4860 3160);
FORCEPROP 2 LASTPIN (-4850 3100) $PN DV13
J 2
(-4860 3110);
DISPLAY 0.617021 (-4860 3110);
PAINT ORANGE (-4860 3110);
FORCEPROP 2 LASTPIN (-4850 2750) $PN DT13
J 2
(-4860 2760);
DISPLAY 0.617021 (-4860 2760);
PAINT ORANGE (-4860 2760);
FORCEPROP 2 LASTPIN (-4850 2700) $PN DT11
J 2
(-4860 2710);
DISPLAY 0.617021 (-4860 2710);
PAINT ORANGE (-4860 2710);
FORCEPROP 2 LASTPIN (-4850 2650) $PN DP11
J 2
(-4860 2660);
DISPLAY 0.617021 (-4860 2660);
PAINT ORANGE (-4860 2660);
FORCEPROP 2 LASTPIN (-4850 2600) $PN DM11
J 2
(-4860 2610);
DISPLAY 0.617021 (-4860 2610);
PAINT ORANGE (-4860 2610);
FORCEPROP 2 LASTPIN (-4850 2250) $PN DM9
J 2
(-4860 2260);
DISPLAY 0.617021 (-4860 2260);
PAINT ORANGE (-4860 2260);
FORCEPROP 2 LASTPIN (-4850 2200) $PN DK9
J 2
(-4860 2210);
DISPLAY 0.617021 (-4860 2210);
PAINT ORANGE (-4860 2210);
FORCEPROP 2 LASTPIN (-4850 2150) $PN DH9
J 2
(-4860 2160);
DISPLAY 0.617021 (-4860 2160);
PAINT ORANGE (-4860 2160);
FORCEPROP 2 LASTPIN (-4850 2100) $PN DE10
J 2
(-4860 2110);
DISPLAY 0.617021 (-4860 2110);
PAINT ORANGE (-4860 2110);
FORCEPROP 2 LASTPIN (-4850 1750) $PN DC10
J 2
(-4860 1760);
DISPLAY 0.617021 (-4860 1760);
PAINT ORANGE (-4860 1760);
FORCEPROP 2 LASTPIN (-4850 1700) $PN DC8
J 2
(-4860 1710);
DISPLAY 0.617021 (-4860 1710);
PAINT ORANGE (-4860 1710);
FORCEPROP 2 LASTPIN (-4850 1650) $PN DA8
J 2
(-4860 1660);
DISPLAY 0.617021 (-4860 1660);
PAINT ORANGE (-4860 1660);
FORCEPROP 2 LASTPIN (-4850 1600) $PN CW8
J 2
(-4860 1610);
DISPLAY 0.617021 (-4860 1610);
PAINT ORANGE (-4860 1610);
FORCEPROP 1 LAST PACK_TYPE BGA1
J 0
(-4800 3800);
PAINT SKYBLUE (-4800 3800);
DISPLAY INVISIBLE (-4800 3800);
FORCEPROP 2 LAST CDS_LIB chpset_lib
J 0
(-4100 2550);
PAINT ORANGE (-4100 2550);
DISPLAY INVISIBLE (-4100 2550);
FORCEPROP 2 LAST SEC_TYPE BGA1
J 0
(-4800 3800);
DISPLAY 1.021277 (-4800 3800);
PAINT ORANGE (-4800 3800);
DISPLAY INVISIBLE (-4800 3800);
FORCEPROP 2 LAST SEC 10
J 0
(-4800 3800);
DISPLAY 0.680851 (-4800 3800);
PAINT MONO (-4800 3800);
DISPLAY INVISIBLE (-4800 3800);
FORCEPROP 2 LAST CDS_LOCATION U5D1
J 0
(-4800 3750);
DISPLAY 0.617021 (-4800 3750);
PAINT AQUA (-4800 3750);
DISPLAY INVISIBLE (-4800 3750);
FORCEPROP 1 LAST PATH I84
J 0
(-4100 3700);
PAINT GREEN (-4100 3700);
DISPLAY INVISIBLE (-4100 3700);
FORCEPROP 0 LAST ROOM CPU0
J 0
(-4800 3850);
DISPLAY 1.021277 (-4800 3850);
PAINT ORANGE (-4800 3850);
DISPLAY INVISIBLE (-4800 3850);
FORCEADD TAP..1
R 2
(-5825 2450);
FORCEPROP 3 LASTPIN (-5775 2450) SIG_NAME P3E_CPU0_PE1_SS_RXP<6>
J 0
(-5765 2460);
DISPLAY 0.659574 (-5765 2460);
PAINT MONO (-5765 2460);
DISPLAY INVISIBLE (-5765 2460);
FORCEPROP 1 LASTPIN (-5775 2450) BN 6
J 2
(-5763 2458);
DISPLAY 0.617021 (-5763 2458);
PAINT PINK (-5763 2458);
FORCEPROP 2 LAST CDS_LIB mstr_standard
J 0
(-5825 2450);
PAINT MONO (-5825 2450);
DISPLAY INVISIBLE (-5825 2450);
FORCEPROP 1 LAST BODY_TYPE PLUMBING
J 2
(-5825 2500);
DISPLAY 1.446809 (-5825 2500);
PAINT GREEN (-5825 2500);
DISPLAY INVISIBLE (-5825 2500);
FORCEPROP 1 LAST HDL_TAP TRUE
J 2
(-6150 2325);
DISPLAY 1.446809 (-6150 2325);
PAINT GREEN (-6150 2325);
DISPLAY INVISIBLE (-6150 2325);
FORCEPROP 1 LAST PATH I9
J 2
(-5823 2450);
DISPLAY 0.872340 (-5823 2450);
PAINT GREEN (-5823 2450);
DISPLAY INVISIBLE (-5823 2450);
FORCEADD PRELIM..10
(-4090 2540);
PAINT GRAY (-4090 2540);
FORCEPROP 2 LAST CDS_LIB mstr_misc
J 0
(-4090 2540);
PAINT ORANGE (-4090 2540);
DISPLAY INVISIBLE (-4090 2540);
FORCEPROP 1 LAST COMMENT_BODY TRUE
J 0
(-4090 2540);
PAINT ORANGE (-4090 2540);
DISPLAY INVISIBLE (-4090 2540);
FORCEADD DESIGN_NOTE..1
(-4600 1300);
FORCEPROP 0 LAST L1 CPU SYMBOLS 1-30 ARE PRELIMINARY AND SUBJECT TO CHANGE
J 0
(-4800 1175);
DISPLAY 1.021277 (-4800 1175);
PAINT ORANGE (-4800 1175);
FORCEPROP 2 LAST CDS_LIB mstr_symbols
J 0
(-4600 1300);
PAINT ORANGE (-4600 1300);
DISPLAY INVISIBLE (-4600 1300);
FORCEPROP 1 LAST COMMENT_BODY TRUE
J 0
(-4575 1400);
DISPLAY 0.978723 (-4575 1400);
PAINT ORANGE (-4575 1400);
DISPLAY INVISIBLE (-4575 1400);
FORCEADD INTEL_CORP_BPAGE..1
(0 0);
FORCEPROP 1 LAST CDS_CON_LAST_MODIFIED Tue Dec 01 11:51:20 2015
J 0
(-1425 325);
DISPLAY 1.340426 (-1425 325);
PAINT GREEN (-1425 325);
DISPLAY INVISIBLE (-1425 325);
FORCEPROP 1 LAST CUSTOM_TXT_CDS <CURRENT_DESIGN_SHEET> OF <TOTAL_DESIGN_SHEETS>
J 0
(-500 25);
PAINT GREEN (-500 25);
FORCEPROP 1 LAST CUSTOM_TXT_CDS <CON_LAST_MODIFIED>
J 0
(-1925 350);
PAINT GREEN (-1925 350);
FORCEPROP 2 LAST CUSTOM_TXT_CDS <XR_PAGE_TITLE>
J 0
(-7890 5250);
DISPLAY 0.638298 (-7890 5250);
PAINT PINK (-7890 5250);
DISPLAY INVISIBLE (-7890 5250);
FORCEPROP 1 LAST SCH_ADDRESS3 Santa Clara, CA 95052-8119
J 0
(-3975 25);
DISPLAY 0.617021 (-3975 25);
PAINT GREEN (-3975 25);
FORCEPROP 1 LAST SCH_ADDRESS2 P.O. BOX 58119
J 0
(-3975 75);
DISPLAY 0.617021 (-3975 75);
PAINT GREEN (-3975 75);
FORCEPROP 1 LAST SCH_ADDRESS1 2200 Mission College Blvd.
J 0
(-3975 125);
DISPLAY 0.617021 (-3975 125);
PAINT GREEN (-3975 125);
FORCEPROP 1 LAST SCH_TITLE SKYLAKE - SKT0 - 10 OF 21
J 0
(-7950 50);
DISPLAY 1.212766 (-7950 50);
PAINT GREEN (-7950 50);
FORCEPROP 1 LAST SCH_NUMBER H4694802
J 0
(-1300 150);
DISPLAY 1.212766 (-1300 150);
PAINT YELLOW (-1300 150);
FORCEPROP 1 LAST SCH_DEPT BESD
J 1
(-4450 100);
DISPLAY 1.212766 (-4450 100);
PAINT YELLOW (-4450 100);
FORCEPROP 1 LAST SCH_REV 2.420
J 0
(-250 150);
DISPLAY 0.978723 (-250 150);
PAINT YELLOW (-250 150);
FORCEPROP 2 LAST PAGE_BORDER TRUE
J 0
(-7890 5250);
DISPLAY 0.851064 (-7890 5250);
PAINT PINK (-7890 5250);
DISPLAY INVISIBLE (-7890 5250);
FORCEPROP 2 LAST CDS_LIB mstr_symbols
J 0
(0 0);
PAINT ORANGE (0 0);
DISPLAY INVISIBLE (0 0);
FORCEPROP 1 LAST COMMENT_BODY TRUE
J 0
(12 12);
DISPLAY 0.638298 (12 12);
PAINT GREEN (12 12);
DISPLAY INVISIBLE (12 12);
FORCEPROP 2 LAST CDS_XR_PAGE_TITLE CR-30 : @BASEBOARD_FAB2_LIB.BASEBOARD_FAB2(SCH_1):PAGE30
J 0
(-7890 5250);
DISPLAY 0.638298 (-7890 5250);
PAINT PINK (-7890 5250);
DISPLAY INVISIBLE (-7890 5250);
WIRE 17 -1 (-2575 3225)(-2575 3275);
WIRE 17 -1 (-2575 3175)(-2575 3225);
WIRE 17 -1 (-2575 3725)(-2575 3275);
WIRE 17 -1 (-2575 3725)(-1200 3725);
FORCEPROP 2 LAST SIG_NAME P3E_CPU0_PE1_PCH_TXN<15:8>
J 0
(-1935 3735);
DISPLAY 0.617021 (-1935 3735);
PAINT ORANGE (-1935 3735);
WIRE 17 -1 (-2575 3125)(-2575 3175);
WIRE 17 -1 (-2575 3125)(-2575 2775);
WIRE 17 -1 (-2575 2775)(-2575 2725);
WIRE 17 -1 (-2575 2675)(-2575 2725);
WIRE 17 -1 (-2575 2675)(-2575 2625);
WIRE 17 -1 (-2575 2225)(-2575 2275);
WIRE 17 -1 (-2575 2225)(-2575 2175);
WIRE 17 -1 (-2575 2175)(-2575 2125);
WIRE 17 -1 (-2575 1775)(-2575 2125);
WIRE 17 -1 (-2575 1725)(-2575 1775);
WIRE 17 -1 (-2575 1675)(-2575 1725);
WIRE 17 -1 (-2575 1675)(-2575 1625);
WIRE 17 -1 (-2575 1625)(-2575 1550);
WIRE 17 -1 (-2575 1550)(-1125 1550);
FORCEPROP 2 LAST SIG_NAME P3E_CPU0_PE1_SS_TXN<7:0>
J 0
(-2060 1560);
DISPLAY 0.617021 (-2060 1560);
PAINT ORANGE (-2060 1560);
WIRE 17 -1 (-2125 3475)(-2125 3525);
WIRE 17 -1 (-2125 3425)(-2125 3475);
WIRE 17 -1 (-2125 3525)(-2125 3575);
WIRE 17 -1 (-2125 3575)(-1200 3575);
FORCEPROP 2 LAST SIG_NAME P3E_CPU0_PE1_PCH_TXP<15:8>
J 0
(-1935 3585);
DISPLAY 0.617021 (-1935 3585);
PAINT ORANGE (-1935 3585);
WIRE 17 -1 (-2125 3375)(-2125 3425);
WIRE 17 -1 (-2125 3025)(-2125 3375);
WIRE 17 -1 (-2125 2975)(-2125 3025);
WIRE 17 -1 (-2125 2925)(-2125 2975);
WIRE 17 -1 (-2125 2875)(-2125 2925);
WIRE 17 -1 (-2125 2525)(-2125 2475);
WIRE 17 -1 (-2125 2475)(-2125 2425);
WIRE 17 -1 (-2125 2425)(-2125 2375);
WIRE 17 -1 (-2125 2025)(-2125 2375);
WIRE 17 -1 (-2125 1975)(-2125 2025);
WIRE 17 -1 (-2125 1925)(-2125 1975);
WIRE 17 -1 (-2125 1925)(-2125 1875);
WIRE 17 -1 (-2125 1875)(-2125 1775);
WIRE 17 -1 (-2125 1775)(-1150 1775);
FORCEPROP 2 LAST SIG_NAME P3E_CPU0_PE1_SS_TXP<7:0>
J 0
(-2035 1785);
DISPLAY 0.617021 (-2035 1785);
PAINT ORANGE (-2035 1785);
WIRE 17 -1 (-5600 3225)(-5600 3275);
WIRE 17 -1 (-5600 3225)(-5600 3175);
WIRE 17 -1 (-5600 3650)(-5600 3275);
WIRE 17 -1 (-5600 3650)(-6725 3650);
FORCEPROP 0 LAST SIG_NAME P3E_CPU0_PE1_PCH_RXN<15:8>
J 0
(-6710 3660);
DISPLAY 0.617021 (-6710 3660);
PAINT ORANGE (-6710 3660);
WIRE 17 -1 (-5600 3175)(-5600 3125);
WIRE 17 -1 (-5600 3125)(-5600 2775);
WIRE 17 -1 (-5600 2775)(-5600 2725);
WIRE 17 -1 (-5600 2725)(-5600 2675);
WIRE 17 -1 (-5600 2675)(-5600 2625);
WIRE 17 -1 (-5600 2225)(-5600 2275);
WIRE 17 -1 (-5600 2225)(-5600 2175);
WIRE 17 -1 (-5600 2175)(-5600 2125);
WIRE 17 -1 (-5600 2125)(-5600 1775);
WIRE 17 -1 (-5600 1775)(-5600 1725);
WIRE 17 -1 (-5600 1725)(-5600 1675);
WIRE 17 -1 (-5600 1675)(-5600 1625);
WIRE 17 -1 (-5600 1625)(-5600 1525);
WIRE 17 -1 (-5600 1525)(-6925 1525);
FORCEPROP 0 LAST SIG_NAME P3E_CPU0_PE1_SS_RXN<7:0>
J 0
(-6860 1535);
DISPLAY 0.617021 (-6860 1535);
PAINT ORANGE (-6860 1535);
WIRE 17 -1 (-6725 3525)(-5875 3525);
FORCEPROP 2 LAST SIG_NAME P3E_CPU0_PE1_PCH_RXP<15:8>
J 0
(-6685 3535);
DISPLAY 0.617021 (-6685 3535);
PAINT ORANGE (-6685 3535);
WIRE 17 -1 (-5875 3475)(-5875 3525);
WIRE 17 -1 (-5875 3425)(-5875 3475);
WIRE 17 -1 (-5875 3375)(-5875 3425);
WIRE 17 -1 (-5875 3025)(-5875 3375);
WIRE 17 -1 (-5875 2975)(-5875 3025);
WIRE 17 -1 (-5875 2925)(-5875 2975);
WIRE 17 -1 (-5875 2925)(-5875 2875);
WIRE 17 -1 (-5875 2475)(-5875 2525);
WIRE 17 -1 (-5875 2425)(-5875 2475);
WIRE 17 -1 (-5875 2375)(-5875 2425);
WIRE 17 -1 (-5875 2025)(-5875 2375);
WIRE 17 -1 (-5875 1975)(-5875 2025);
WIRE 17 -1 (-5875 1925)(-5875 1975);
WIRE 17 -1 (-5875 1875)(-5875 1925);
WIRE 17 -1 (-5875 1875)(-5875 1800);
WIRE 17 -1 (-5875 1800)(-6925 1800);
FORCEPROP 2 LAST SIG_NAME P3E_CPU0_PE1_SS_RXP<7:0>
J 0
(-6885 1810);
DISPLAY 0.617021 (-6885 1810);
PAINT ORANGE (-6885 1810);
WIRE 16 -1 (-5500 1750)(-4850 1750);
WIRE 16 -1 (-4850 1850)(-5775 1850);
WIRE 16 -1 (-5775 1900)(-4850 1900);
WIRE 16 -1 (-5775 1950)(-4850 1950);
WIRE 16 -1 (-5775 2000)(-4850 2000);
WIRE 16 -1 (-4850 1600)(-5500 1600);
WIRE 16 -1 (-5500 1650)(-4850 1650);
WIRE 16 -1 (-5500 1700)(-4850 1700);
WIRE 16 -1 (-5775 2350)(-4850 2350);
WIRE 16 -1 (-5775 2400)(-4850 2400);
WIRE 16 -1 (-5775 2450)(-4850 2450);
WIRE 16 -1 (-4850 2500)(-5775 2500);
WIRE 16 -1 (-5775 2850)(-4850 2850);
WIRE 16 -1 (-5775 2900)(-4850 2900);
WIRE 16 -1 (-5775 2950)(-4850 2950);
WIRE 16 -1 (-5775 3000)(-4850 3000);
WIRE 16 -1 (-5775 3350)(-4850 3350);
WIRE 16 -1 (-5775 3400)(-4850 3400);
WIRE 16 -1 (-5775 3450)(-4850 3450);
WIRE 16 -1 (-5775 3500)(-4850 3500);
WIRE 16 -1 (-5500 2100)(-4850 2100);
WIRE 16 -1 (-5500 2150)(-4850 2150);
WIRE 16 -1 (-5500 2200)(-4850 2200);
WIRE 16 -1 (-4850 2250)(-5500 2250);
WIRE 16 -1 (-5500 2600)(-4850 2600);
WIRE 16 -1 (-5500 2650)(-4850 2650);
WIRE 16 -1 (-4850 2700)(-5500 2700);
WIRE 16 -1 (-5500 2750)(-4850 2750);
WIRE 16 -1 (-5500 3100)(-4850 3100);
WIRE 16 -1 (-5500 3150)(-4850 3150);
WIRE 16 -1 (-4850 3200)(-5500 3200);
WIRE 16 -1 (-5500 3250)(-4850 3250);
WIRE 16 -1 (-2225 1850)(-3350 1850);
WIRE 16 -1 (-2225 1900)(-3350 1900);
WIRE 16 -1 (-2225 1950)(-3350 1950);
WIRE 16 -1 (-2225 2000)(-3350 2000);
WIRE 16 -1 (-2675 1600)(-3350 1600);
WIRE 16 -1 (-3350 1650)(-2675 1650);
WIRE 16 -1 (-2675 1700)(-3350 1700);
WIRE 16 -1 (-2675 1750)(-3350 1750);
WIRE 16 -1 (-3350 2350)(-2225 2350);
WIRE 16 -1 (-3350 2400)(-2225 2400);
WIRE 16 -1 (-3350 2450)(-2225 2450);
WIRE 16 -1 (-3350 2500)(-2225 2500);
WIRE 16 -1 (-3350 2850)(-2225 2850);
WIRE 16 -1 (-2225 2900)(-3350 2900);
WIRE 16 -1 (-3350 2950)(-2225 2950);
WIRE 16 -1 (-3350 3000)(-2225 3000);
WIRE 16 -1 (-2225 3350)(-3350 3350);
WIRE 16 -1 (-2225 3400)(-3350 3400);
WIRE 16 -1 (-2225 3450)(-3350 3450);
WIRE 16 -1 (-2225 3500)(-3350 3500);
WIRE 16 -1 (-3350 2100)(-2675 2100);
WIRE 16 -1 (-3350 2150)(-2675 2150);
WIRE 16 -1 (-3350 2200)(-2675 2200);
WIRE 16 -1 (-2675 2250)(-3350 2250);
WIRE 16 -1 (-2675 2600)(-3350 2600);
WIRE 16 -1 (-2675 2650)(-3350 2650);
WIRE 16 -1 (-2675 2700)(-3350 2700);
WIRE 16 -1 (-2675 2750)(-3350 2750);
WIRE 16 -1 (-2675 3100)(-3350 3100);
WIRE 16 -1 (-2675 3150)(-3350 3150);
WIRE 16 -1 (-3350 3200)(-2675 3200);
WIRE 16 -1 (-3350 3250)(-2675 3250);
FORCENOTE
ROOM=CPU0
(-7925 375) 0;
DISPLAY LEFT (-7925 375);
DISPLAY 1.723404 (-7925 375);
PAINT PURPLE (-7925 375);
FORCENOTE
BOM_COST=PROC_SOCKET
(-7925 250) 0;
DISPLAY LEFT (-7925 250);
DISPLAY 1.723404 (-7925 250);
PAINT PURPLE (-7925 250);
FORCENOTE
TO: 
(-7125 1375) 0;
DISPLAY LEFT (-7125 1375);
DISPLAY 1.021277 (-7125 1375);
PAINT PURPLE (-7125 1375);
FORCENOTE
STRAIGHT TO PCH PCIEUP
(-7175 3350) 0;
DISPLAY LEFT (-7175 3350);
DISPLAY 1.021277 (-7175 3350);
PAINT PURPLE (-7175 3350);
FORCENOTE
PCH PCIEUP/SS STEERING OPTION
(-7125 1300) 0;
DISPLAY LEFT (-7125 1300);
DISPLAY 1.021277 (-7125 1300);
PAINT PURPLE (-7125 1300);
FORCENOTE
TO: 
(-1300 1400) 0;
DISPLAY LEFT (-1300 1400);
DISPLAY 1.021277 (-1300 1400);
PAINT PURPLE (-1300 1400);
FORCENOTE
STRAIGHT TO PCH PCIEUP
(-1450 3375) 0;
DISPLAY LEFT (-1450 3375);
DISPLAY 1.021277 (-1450 3375);
PAINT PURPLE (-1450 3375);
FORCENOTE
PCH PCIEUP/SS STEERING OPTION
(-1300 1325) 0;
DISPLAY LEFT (-1300 1325);
DISPLAY 1.021277 (-1300 1325);
PAINT PURPLE (-1300 1325);
QUIT
